FILE_TYPE = MACRO_DRAWING;
SET COLOR_WIRE YELLOW;
SET COLOR_PROP MONO;
SET COLOR_DOT WHITE;
SET COLOR_ARC YELLOW;
SET COLOR_BODY GREEN;
SET COLOR_NOTE MONO;
SET PROP_DISPLAY VALUE;
SET PAGE_NUMBER P188;
FORCEADD OFFPAGE..4
(1400 3075);
FORCEPROP 2 LAST $XR0 118 
J 0
(1586 3075);
DISPLAY 0.638298 (1586 3075);
PAINT MONO (1586 3075);
FORCEPROP 2 LAST BOM_COST SB
J 0
(1150 3125);
DISPLAY 1.361702 (1150 3125);
PAINT ORANGE (1150 3125);
DISPLAY INVISIBLE (1150 3125);
FORCEPROP 2 LAST ROOM SB
J 0
(1150 3125);
DISPLAY 1.361702 (1150 3125);
PAINT ORANGE (1150 3125);
DISPLAY INVISIBLE (1150 3125);
FORCEPROP 2 LAST CDS_LIB mstr_standard
J 0
(1400 3075);
PAINT ORANGE (1400 3075);
DISPLAY INVISIBLE (1400 3075);
FORCEPROP 1 LAST OFFPAGE TRUE
J 0
(1725 2950);
DISPLAY 0.872340 (1725 2950);
PAINT GREEN (1725 2950);
DISPLAY INVISIBLE (1725 2950);
FORCEPROP 1 LAST COMMENT_BODY TRUE
J 0
(1375 2975);
DISPLAY 0.872340 (1375 2975);
PAINT GREEN (1375 2975);
DISPLAY INVISIBLE (1375 2975);
FORCEPROP 2 LAST PATH I10
J 0
(1600 3125);
DISPLAY 1.021277 (1600 3125);
PAINT ORANGE (1600 3125);
DISPLAY INVISIBLE (1600 3125);
FORCEADD OFFPAGE..3
(-2450 1825);
FORCEPROP 2 LAST $XR0 120 
J 0
(-2236 1825);
DISPLAY 0.638298 (-2236 1825);
PAINT MONO (-2236 1825);
FORCEPROP 2 LAST $XR1 188 
J 0
(-2116 1825);
DISPLAY 0.638298 (-2116 1825);
PAINT MONO (-2116 1825);
FORCEPROP 2 LAST ROOM SB
J 0
(-2700 1875);
DISPLAY 1.361702 (-2700 1875);
PAINT ORANGE (-2700 1875);
DISPLAY INVISIBLE (-2700 1875);
FORCEPROP 2 LAST BOM_COST SB
J 0
(-2700 1875);
DISPLAY 1.361702 (-2700 1875);
PAINT ORANGE (-2700 1875);
DISPLAY INVISIBLE (-2700 1875);
FORCEPROP 2 LAST CDS_LIB mstr_standard
J 0
(-2450 1825);
PAINT ORANGE (-2450 1825);
DISPLAY INVISIBLE (-2450 1825);
FORCEPROP 1 LAST OFFPAGE TRUE
J 0
(-2125 1700);
DISPLAY 0.872340 (-2125 1700);
PAINT GREEN (-2125 1700);
DISPLAY INVISIBLE (-2125 1700);
FORCEPROP 1 LAST COMMENT_BODY TRUE
J 0
(-2500 1725);
DISPLAY 0.872340 (-2500 1725);
PAINT GREEN (-2500 1725);
DISPLAY INVISIBLE (-2500 1725);
FORCEPROP 2 LAST PATH I100
J 0
(-2250 1900);
DISPLAY 1.021277 (-2250 1900);
PAINT ORANGE (-2250 1900);
DISPLAY INVISIBLE (-2250 1900);
FORCEADD OFFPAGE..3
(-2450 2425);
FORCEPROP 2 LAST $XR0 120 
J 0
(-2236 2425);
DISPLAY 0.638298 (-2236 2425);
PAINT MONO (-2236 2425);
FORCEPROP 2 LAST $XR1 188 
J 0
(-2116 2425);
DISPLAY 0.638298 (-2116 2425);
PAINT MONO (-2116 2425);
FORCEPROP 2 LAST ROOM SB
J 0
(-2700 2475);
DISPLAY 1.361702 (-2700 2475);
PAINT ORANGE (-2700 2475);
DISPLAY INVISIBLE (-2700 2475);
FORCEPROP 2 LAST BOM_COST SB
J 0
(-2700 2475);
DISPLAY 1.361702 (-2700 2475);
PAINT ORANGE (-2700 2475);
DISPLAY INVISIBLE (-2700 2475);
FORCEPROP 2 LAST CDS_LIB mstr_standard
J 0
(-2450 2425);
PAINT ORANGE (-2450 2425);
DISPLAY INVISIBLE (-2450 2425);
FORCEPROP 1 LAST OFFPAGE TRUE
J 0
(-2125 2300);
DISPLAY 0.872340 (-2125 2300);
PAINT GREEN (-2125 2300);
DISPLAY INVISIBLE (-2125 2300);
FORCEPROP 1 LAST COMMENT_BODY TRUE
J 0
(-2500 2325);
DISPLAY 0.872340 (-2500 2325);
PAINT GREEN (-2500 2325);
DISPLAY INVISIBLE (-2500 2325);
FORCEPROP 2 LAST PATH I101
J 0
(-2250 2500);
DISPLAY 1.021277 (-2250 2500);
PAINT ORANGE (-2250 2500);
DISPLAY INVISIBLE (-2250 2500);
FORCEADD OFFPAGE..3
(-2450 3050);
FORCEPROP 2 LAST $XR0 120 
J 0
(-2236 3050);
DISPLAY 0.638298 (-2236 3050);
PAINT MONO (-2236 3050);
FORCEPROP 2 LAST $XR1 188 
J 0
(-2116 3050);
DISPLAY 0.638298 (-2116 3050);
PAINT MONO (-2116 3050);
FORCEPROP 2 LAST CDS_LIB mstr_standard
J 0
(-2450 3050);
PAINT ORANGE (-2450 3050);
DISPLAY INVISIBLE (-2450 3050);
FORCEPROP 2 LAST BOM_COST SB
J 0
(-2700 3100);
DISPLAY 1.361702 (-2700 3100);
PAINT ORANGE (-2700 3100);
DISPLAY INVISIBLE (-2700 3100);
FORCEPROP 2 LAST ROOM SB
J 0
(-2700 3100);
DISPLAY 1.361702 (-2700 3100);
PAINT ORANGE (-2700 3100);
DISPLAY INVISIBLE (-2700 3100);
FORCEPROP 1 LAST OFFPAGE TRUE
J 0
(-2125 2925);
DISPLAY 0.872340 (-2125 2925);
PAINT GREEN (-2125 2925);
DISPLAY INVISIBLE (-2125 2925);
FORCEPROP 1 LAST COMMENT_BODY TRUE
J 0
(-2500 2950);
DISPLAY 0.872340 (-2500 2950);
PAINT GREEN (-2500 2950);
DISPLAY INVISIBLE (-2500 2950);
FORCEPROP 2 LAST PATH I102
J 0
(-2250 3125);
DISPLAY 1.021277 (-2250 3125);
PAINT ORANGE (-2250 3125);
DISPLAY INVISIBLE (-2250 3125);
FORCEADD OFFPAGE..3
(-2450 3650);
FORCEPROP 2 LAST $XR0 120 
J 0
(-2236 3650);
DISPLAY 0.638298 (-2236 3650);
PAINT MONO (-2236 3650);
FORCEPROP 2 LAST $XR1 188 
J 0
(-2116 3650);
DISPLAY 0.638298 (-2116 3650);
PAINT MONO (-2116 3650);
FORCEPROP 2 LAST CDS_LIB mstr_standard
J 0
(-2450 3650);
PAINT ORANGE (-2450 3650);
DISPLAY INVISIBLE (-2450 3650);
FORCEPROP 2 LAST BOM_COST SB
J 0
(-2700 3700);
DISPLAY 1.361702 (-2700 3700);
PAINT ORANGE (-2700 3700);
DISPLAY INVISIBLE (-2700 3700);
FORCEPROP 2 LAST ROOM SB
J 0
(-2700 3700);
DISPLAY 1.361702 (-2700 3700);
PAINT ORANGE (-2700 3700);
DISPLAY INVISIBLE (-2700 3700);
FORCEPROP 1 LAST OFFPAGE TRUE
J 0
(-2125 3525);
DISPLAY 0.872340 (-2125 3525);
PAINT GREEN (-2125 3525);
DISPLAY INVISIBLE (-2125 3525);
FORCEPROP 1 LAST COMMENT_BODY TRUE
J 0
(-2500 3550);
DISPLAY 0.872340 (-2500 3550);
PAINT GREEN (-2500 3550);
DISPLAY INVISIBLE (-2500 3550);
FORCEPROP 2 LAST PATH I103
J 0
(-2250 3725);
DISPLAY 1.021277 (-2250 3725);
PAINT ORANGE (-2250 3725);
DISPLAY INVISIBLE (-2250 3725);
FORCEADD OFFPAGE..6
(-1400 2475);
FORCEPROP 2 LAST $XR0 120 
J 0
(-1680 2475);
DISPLAY 0.638298 (-1680 2475);
PAINT MONO (-1680 2475);
FORCEPROP 2 LAST $XR1 188 
J 0
(-1800 2475);
DISPLAY 0.638298 (-1800 2475);
PAINT MONO (-1800 2475);
FORCEPROP 2 LAST CDS_LIB mstr_standard
J 0
(-1400 2475);
PAINT ORANGE (-1400 2475);
DISPLAY INVISIBLE (-1400 2475);
FORCEPROP 2 LAST ROOM SB
J 0
(-1650 2525);
DISPLAY 1.361702 (-1650 2525);
PAINT ORANGE (-1650 2525);
DISPLAY INVISIBLE (-1650 2525);
FORCEPROP 2 LAST BOM_COST SB
J 0
(-1650 2525);
DISPLAY 1.361702 (-1650 2525);
PAINT ORANGE (-1650 2525);
DISPLAY INVISIBLE (-1650 2525);
FORCEPROP 1 LAST OFFPAGE TRUE
J 0
(-1075 2350);
DISPLAY 0.872340 (-1075 2350);
PAINT GREEN (-1075 2350);
DISPLAY INVISIBLE (-1075 2350);
FORCEPROP 1 LAST COMMENT_BODY TRUE
J 0
(-1300 2400);
DISPLAY 0.872340 (-1300 2400);
PAINT GREEN (-1300 2400);
DISPLAY INVISIBLE (-1300 2400);
FORCEPROP 2 LAST PATH I104
J 0
(-1350 2550);
DISPLAY 1.021277 (-1350 2550);
PAINT ORANGE (-1350 2550);
DISPLAY INVISIBLE (-1350 2550);
FORCEADD OFFPAGE..1
(-1400 2525);
FORCEPROP 2 LAST $XR0 120 
J 0
(-1682 2525);
DISPLAY 0.638298 (-1682 2525);
PAINT MONO (-1682 2525);
FORCEPROP 2 LAST $XR1 188 
J 0
(-1802 2525);
DISPLAY 0.638298 (-1802 2525);
PAINT MONO (-1802 2525);
FORCEPROP 2 LAST CDS_LIB mstr_standard
J 0
(-1400 2525);
PAINT ORANGE (-1400 2525);
DISPLAY INVISIBLE (-1400 2525);
FORCEPROP 2 LAST BOM_COST SB
J 0
(-1650 2575);
DISPLAY 1.361702 (-1650 2575);
PAINT ORANGE (-1650 2575);
DISPLAY INVISIBLE (-1650 2575);
FORCEPROP 2 LAST ROOM SB
J 0
(-1650 2575);
DISPLAY 1.361702 (-1650 2575);
PAINT ORANGE (-1650 2575);
DISPLAY INVISIBLE (-1650 2575);
FORCEPROP 1 LAST OFFPAGE TRUE
J 0
(-1075 2400);
DISPLAY 0.872340 (-1075 2400);
PAINT GREEN (-1075 2400);
DISPLAY INVISIBLE (-1075 2400);
FORCEPROP 1 LAST COMMENT_BODY TRUE
J 0
(-1275 2425);
DISPLAY 0.872340 (-1275 2425);
PAINT GREEN (-1275 2425);
DISPLAY INVISIBLE (-1275 2425);
FORCEPROP 2 LAST PATH I105
J 0
(-1350 2600);
DISPLAY 1.021277 (-1350 2600);
PAINT ORANGE (-1350 2600);
DISPLAY INVISIBLE (-1350 2600);
FORCEADD OFFPAGE..6
(-1400 2325);
FORCEPROP 2 LAST $XR0 120 
J 0
(-1680 2325);
DISPLAY 0.638298 (-1680 2325);
PAINT MONO (-1680 2325);
FORCEPROP 2 LAST $XR1 188 
J 0
(-1800 2325);
DISPLAY 0.638298 (-1800 2325);
PAINT MONO (-1800 2325);
FORCEPROP 2 LAST BOM_COST SB
J 0
(-1650 2375);
DISPLAY 1.361702 (-1650 2375);
PAINT ORANGE (-1650 2375);
DISPLAY INVISIBLE (-1650 2375);
FORCEPROP 2 LAST ROOM SB
J 0
(-1650 2375);
DISPLAY 1.361702 (-1650 2375);
PAINT ORANGE (-1650 2375);
DISPLAY INVISIBLE (-1650 2375);
FORCEPROP 2 LAST CDS_LIB mstr_standard
J 0
(-1400 2325);
PAINT ORANGE (-1400 2325);
DISPLAY INVISIBLE (-1400 2325);
FORCEPROP 1 LAST OFFPAGE TRUE
J 0
(-1075 2200);
DISPLAY 0.872340 (-1075 2200);
PAINT GREEN (-1075 2200);
DISPLAY INVISIBLE (-1075 2200);
FORCEPROP 1 LAST COMMENT_BODY TRUE
J 0
(-1300 2250);
DISPLAY 0.872340 (-1300 2250);
PAINT GREEN (-1300 2250);
DISPLAY INVISIBLE (-1300 2250);
FORCEPROP 2 LAST PATH I106
J 0
(-1350 2400);
DISPLAY 1.021277 (-1350 2400);
PAINT ORANGE (-1350 2400);
DISPLAY INVISIBLE (-1350 2400);
FORCEADD OFFPAGE..1
(-1400 2375);
FORCEPROP 2 LAST $XR0 120 
J 0
(-1682 2375);
DISPLAY 0.638298 (-1682 2375);
PAINT MONO (-1682 2375);
FORCEPROP 2 LAST $XR1 188 
J 0
(-1802 2375);
DISPLAY 0.638298 (-1802 2375);
PAINT MONO (-1802 2375);
FORCEPROP 2 LAST CDS_LIB mstr_standard
J 0
(-1400 2375);
PAINT ORANGE (-1400 2375);
DISPLAY INVISIBLE (-1400 2375);
FORCEPROP 2 LAST BOM_COST SB
J 0
(-1650 2425);
DISPLAY 1.361702 (-1650 2425);
PAINT ORANGE (-1650 2425);
DISPLAY INVISIBLE (-1650 2425);
FORCEPROP 2 LAST ROOM SB
J 0
(-1650 2425);
DISPLAY 1.361702 (-1650 2425);
PAINT ORANGE (-1650 2425);
DISPLAY INVISIBLE (-1650 2425);
FORCEPROP 1 LAST OFFPAGE TRUE
J 0
(-1075 2250);
DISPLAY 0.872340 (-1075 2250);
PAINT GREEN (-1075 2250);
DISPLAY INVISIBLE (-1075 2250);
FORCEPROP 1 LAST COMMENT_BODY TRUE
J 0
(-1275 2275);
DISPLAY 0.872340 (-1275 2275);
PAINT GREEN (-1275 2275);
DISPLAY INVISIBLE (-1275 2275);
FORCEPROP 2 LAST PATH I107
J 0
(-1350 2450);
DISPLAY 1.021277 (-1350 2450);
PAINT ORANGE (-1350 2450);
DISPLAY INVISIBLE (-1350 2450);
FORCEADD OFFPAGE..1
(-1400 2825);
FORCEPROP 2 LAST $XR0 120 
J 0
(-1682 2825);
DISPLAY 0.638298 (-1682 2825);
PAINT MONO (-1682 2825);
FORCEPROP 2 LAST $XR1 188 
J 0
(-1802 2825);
DISPLAY 0.638298 (-1802 2825);
PAINT MONO (-1802 2825);
FORCEPROP 2 LAST ROOM SB
J 0
(-1650 2875);
DISPLAY 1.361702 (-1650 2875);
PAINT ORANGE (-1650 2875);
DISPLAY INVISIBLE (-1650 2875);
FORCEPROP 2 LAST BOM_COST SB
J 0
(-1650 2875);
DISPLAY 1.361702 (-1650 2875);
PAINT ORANGE (-1650 2875);
DISPLAY INVISIBLE (-1650 2875);
FORCEPROP 2 LAST CDS_LIB mstr_standard
J 0
(-1400 2825);
PAINT ORANGE (-1400 2825);
DISPLAY INVISIBLE (-1400 2825);
FORCEPROP 1 LAST OFFPAGE TRUE
J 0
(-1075 2700);
DISPLAY 0.872340 (-1075 2700);
PAINT GREEN (-1075 2700);
DISPLAY INVISIBLE (-1075 2700);
FORCEPROP 1 LAST COMMENT_BODY TRUE
J 0
(-1275 2725);
DISPLAY 0.872340 (-1275 2725);
PAINT GREEN (-1275 2725);
DISPLAY INVISIBLE (-1275 2725);
FORCEPROP 2 LAST PATH I108
J 0
(-1350 2900);
DISPLAY 1.021277 (-1350 2900);
PAINT ORANGE (-1350 2900);
DISPLAY INVISIBLE (-1350 2900);
FORCEADD OFFPAGE..6
(-1400 2775);
FORCEPROP 2 LAST $XR0 120 
J 0
(-1680 2775);
DISPLAY 0.638298 (-1680 2775);
PAINT MONO (-1680 2775);
FORCEPROP 2 LAST $XR1 188 
J 0
(-1800 2775);
DISPLAY 0.638298 (-1800 2775);
PAINT MONO (-1800 2775);
FORCEPROP 2 LAST CDS_LIB mstr_standard
J 0
(-1400 2775);
PAINT ORANGE (-1400 2775);
DISPLAY INVISIBLE (-1400 2775);
FORCEPROP 2 LAST ROOM SB
J 0
(-1650 2825);
DISPLAY 1.361702 (-1650 2825);
PAINT ORANGE (-1650 2825);
DISPLAY INVISIBLE (-1650 2825);
FORCEPROP 2 LAST BOM_COST SB
J 0
(-1650 2825);
DISPLAY 1.361702 (-1650 2825);
PAINT ORANGE (-1650 2825);
DISPLAY INVISIBLE (-1650 2825);
FORCEPROP 1 LAST OFFPAGE TRUE
J 0
(-1075 2650);
DISPLAY 0.872340 (-1075 2650);
PAINT GREEN (-1075 2650);
DISPLAY INVISIBLE (-1075 2650);
FORCEPROP 1 LAST COMMENT_BODY TRUE
J 0
(-1300 2700);
DISPLAY 0.872340 (-1300 2700);
PAINT GREEN (-1300 2700);
DISPLAY INVISIBLE (-1300 2700);
FORCEPROP 2 LAST PATH I109
J 0
(-1350 2850);
DISPLAY 1.021277 (-1350 2850);
PAINT ORANGE (-1350 2850);
DISPLAY INVISIBLE (-1350 2850);
FORCEADD OFFPAGE..4
(1400 3125);
FORCEPROP 2 LAST $XR0 118 
J 0
(1586 3125);
DISPLAY 0.638298 (1586 3125);
PAINT MONO (1586 3125);
FORCEPROP 2 LAST BOM_COST SB
J 0
(1150 3175);
DISPLAY 1.361702 (1150 3175);
PAINT ORANGE (1150 3175);
DISPLAY INVISIBLE (1150 3175);
FORCEPROP 2 LAST ROOM SB
J 0
(1150 3175);
DISPLAY 1.361702 (1150 3175);
PAINT ORANGE (1150 3175);
DISPLAY INVISIBLE (1150 3175);
FORCEPROP 2 LAST CDS_LIB mstr_standard
J 0
(1400 3125);
PAINT ORANGE (1400 3125);
DISPLAY INVISIBLE (1400 3125);
FORCEPROP 1 LAST OFFPAGE TRUE
J 0
(1725 3000);
DISPLAY 0.872340 (1725 3000);
PAINT GREEN (1725 3000);
DISPLAY INVISIBLE (1725 3000);
FORCEPROP 1 LAST COMMENT_BODY TRUE
J 0
(1375 3025);
DISPLAY 0.872340 (1375 3025);
PAINT GREEN (1375 3025);
DISPLAY INVISIBLE (1375 3025);
FORCEPROP 2 LAST PATH I11
J 0
(1600 3175);
DISPLAY 1.021277 (1600 3175);
PAINT ORANGE (1600 3175);
DISPLAY INVISIBLE (1600 3175);
FORCEADD OFFPAGE..3
(1400 2325);
FORCEPROP 2 LAST $XR0 120 
J 0
(1614 2325);
DISPLAY 0.638298 (1614 2325);
PAINT MONO (1614 2325);
FORCEPROP 2 LAST $XR1 188 
J 0
(1734 2325);
DISPLAY 0.638298 (1734 2325);
PAINT MONO (1734 2325);
FORCEPROP 2 LAST CDS_LIB mstr_standard
J 0
(1400 2325);
PAINT ORANGE (1400 2325);
DISPLAY INVISIBLE (1400 2325);
FORCEPROP 2 LAST ROOM SB
J 0
(1150 2375);
DISPLAY 1.361702 (1150 2375);
PAINT ORANGE (1150 2375);
DISPLAY INVISIBLE (1150 2375);
FORCEPROP 2 LAST BOM_COST SB
J 0
(1150 2375);
DISPLAY 1.361702 (1150 2375);
PAINT ORANGE (1150 2375);
DISPLAY INVISIBLE (1150 2375);
FORCEPROP 1 LAST OFFPAGE TRUE
J 0
(1725 2200);
DISPLAY 0.872340 (1725 2200);
PAINT GREEN (1725 2200);
DISPLAY INVISIBLE (1725 2200);
FORCEPROP 1 LAST COMMENT_BODY TRUE
J 0
(1350 2225);
DISPLAY 0.872340 (1350 2225);
PAINT GREEN (1350 2225);
DISPLAY INVISIBLE (1350 2225);
FORCEPROP 2 LAST PATH I110
J 0
(1600 2400);
DISPLAY 1.021277 (1600 2400);
PAINT ORANGE (1600 2400);
DISPLAY INVISIBLE (1600 2400);
FORCEADD OFFPAGE..4
(1400 2375);
FORCEPROP 2 LAST $XR0 120 
J 0
(1586 2375);
DISPLAY 0.638298 (1586 2375);
PAINT MONO (1586 2375);
FORCEPROP 2 LAST $XR1 188 
J 0
(1706 2375);
DISPLAY 0.638298 (1706 2375);
PAINT MONO (1706 2375);
FORCEPROP 2 LAST BOM_COST SB
J 0
(1150 2425);
DISPLAY 1.361702 (1150 2425);
PAINT ORANGE (1150 2425);
DISPLAY INVISIBLE (1150 2425);
FORCEPROP 2 LAST ROOM SB
J 0
(1150 2425);
DISPLAY 1.361702 (1150 2425);
PAINT ORANGE (1150 2425);
DISPLAY INVISIBLE (1150 2425);
FORCEPROP 2 LAST CDS_LIB mstr_standard
J 0
(1400 2375);
PAINT ORANGE (1400 2375);
DISPLAY INVISIBLE (1400 2375);
FORCEPROP 1 LAST OFFPAGE TRUE
J 0
(1725 2250);
DISPLAY 0.872340 (1725 2250);
PAINT GREEN (1725 2250);
DISPLAY INVISIBLE (1725 2250);
FORCEPROP 1 LAST COMMENT_BODY TRUE
J 0
(1375 2275);
DISPLAY 0.872340 (1375 2275);
PAINT GREEN (1375 2275);
DISPLAY INVISIBLE (1375 2275);
FORCEPROP 2 LAST PATH I111
J 0
(1575 2450);
DISPLAY 1.021277 (1575 2450);
PAINT ORANGE (1575 2450);
DISPLAY INVISIBLE (1575 2450);
FORCEADD OFFPAGE..2
(1400 3525);
FORCEPROP 2 LAST $XR0 120 
J 0
(1589 3525);
DISPLAY 0.638298 (1589 3525);
PAINT MONO (1589 3525);
FORCEPROP 2 LAST CDS_LIB mstr_standard
J 0
(1400 3525);
PAINT ORANGE (1400 3525);
DISPLAY INVISIBLE (1400 3525);
FORCEPROP 2 LAST ROOM SB
J 0
(1150 3575);
DISPLAY 1.361702 (1150 3575);
PAINT ORANGE (1150 3575);
DISPLAY INVISIBLE (1150 3575);
FORCEPROP 2 LAST BOM_COST SB
J 0
(1150 3575);
DISPLAY 1.361702 (1150 3575);
PAINT ORANGE (1150 3575);
DISPLAY INVISIBLE (1150 3575);
FORCEPROP 1 LAST OFFPAGE TRUE
J 0
(1725 3400);
DISPLAY 0.872340 (1725 3400);
PAINT GREEN (1725 3400);
DISPLAY INVISIBLE (1725 3400);
FORCEPROP 1 LAST COMMENT_BODY TRUE
J 0
(1355 3430);
DISPLAY 0.872340 (1355 3430);
PAINT GREEN (1355 3430);
DISPLAY INVISIBLE (1355 3430);
FORCEPROP 2 LAST PATH I112
J 0
(1575 3600);
DISPLAY 1.021277 (1575 3600);
PAINT ORANGE (1575 3600);
DISPLAY INVISIBLE (1575 3600);
FORCEADD OFFPAGE..2
(1400 3575);
FORCEPROP 2 LAST $XR0 120 
J 0
(1589 3575);
DISPLAY 0.638298 (1589 3575);
PAINT MONO (1589 3575);
FORCEPROP 2 LAST BOM_COST SB
J 0
(1150 3625);
DISPLAY 1.361702 (1150 3625);
PAINT ORANGE (1150 3625);
DISPLAY INVISIBLE (1150 3625);
FORCEPROP 2 LAST ROOM SB
J 0
(1150 3625);
DISPLAY 1.361702 (1150 3625);
PAINT ORANGE (1150 3625);
DISPLAY INVISIBLE (1150 3625);
FORCEPROP 2 LAST CDS_LIB mstr_standard
J 0
(1400 3575);
PAINT ORANGE (1400 3575);
DISPLAY INVISIBLE (1400 3575);
FORCEPROP 1 LAST OFFPAGE TRUE
J 0
(1725 3450);
DISPLAY 0.872340 (1725 3450);
PAINT GREEN (1725 3450);
DISPLAY INVISIBLE (1725 3450);
FORCEPROP 1 LAST COMMENT_BODY TRUE
J 0
(1355 3480);
DISPLAY 0.872340 (1355 3480);
PAINT GREEN (1355 3480);
DISPLAY INVISIBLE (1355 3480);
FORCEPROP 2 LAST PATH I113
J 0
(1575 3650);
DISPLAY 1.021277 (1575 3650);
PAINT ORANGE (1575 3650);
DISPLAY INVISIBLE (1575 3650);
FORCEADD OFFPAGE..5
(-1400 2275);
FORCEPROP 2 LAST $XR0 120 
J 0
(-1685 2275);
DISPLAY 0.638298 (-1685 2275);
PAINT MONO (-1685 2275);
FORCEPROP 2 LAST ROOM SB
J 0
(-1650 2325);
DISPLAY 1.361702 (-1650 2325);
PAINT ORANGE (-1650 2325);
DISPLAY INVISIBLE (-1650 2325);
FORCEPROP 2 LAST BOM_COST SB
J 0
(-1650 2325);
DISPLAY 1.361702 (-1650 2325);
PAINT ORANGE (-1650 2325);
DISPLAY INVISIBLE (-1650 2325);
FORCEPROP 2 LAST CDS_LIB mstr_standard
J 0
(-1400 2275);
PAINT ORANGE (-1400 2275);
DISPLAY INVISIBLE (-1400 2275);
FORCEPROP 1 LAST OFFPAGE TRUE
J 0
(-1075 2150);
DISPLAY 0.872340 (-1075 2150);
PAINT GREEN (-1075 2150);
DISPLAY INVISIBLE (-1075 2150);
FORCEPROP 1 LAST COMMENT_BODY TRUE
J 0
(-1300 2200);
DISPLAY 0.872340 (-1300 2200);
PAINT GREEN (-1300 2200);
DISPLAY INVISIBLE (-1300 2200);
FORCEPROP 2 LAST PATH I114
J 0
(-1350 2350);
DISPLAY 1.021277 (-1350 2350);
PAINT ORANGE (-1350 2350);
DISPLAY INVISIBLE (-1350 2350);
FORCEADD OFFPAGE..5
(-1400 2225);
FORCEPROP 2 LAST $XR0 120 
J 0
(-1655 2225);
DISPLAY 0.638298 (-1655 2225);
PAINT MONO (-1655 2225);
FORCEPROP 2 LAST BOM_COST SB
J 0
(-1650 2275);
DISPLAY 1.361702 (-1650 2275);
PAINT ORANGE (-1650 2275);
DISPLAY INVISIBLE (-1650 2275);
FORCEPROP 2 LAST ROOM SB
J 0
(-1650 2275);
DISPLAY 1.361702 (-1650 2275);
PAINT ORANGE (-1650 2275);
DISPLAY INVISIBLE (-1650 2275);
FORCEPROP 2 LAST CDS_LIB mstr_standard
J 0
(-1400 2225);
PAINT ORANGE (-1400 2225);
DISPLAY INVISIBLE (-1400 2225);
FORCEPROP 1 LAST OFFPAGE TRUE
J 0
(-1075 2100);
DISPLAY 0.872340 (-1075 2100);
PAINT GREEN (-1075 2100);
DISPLAY INVISIBLE (-1075 2100);
FORCEPROP 1 LAST COMMENT_BODY TRUE
J 0
(-1300 2150);
DISPLAY 0.872340 (-1300 2150);
PAINT GREEN (-1300 2150);
DISPLAY INVISIBLE (-1300 2150);
FORCEPROP 2 LAST PATH I115
J 0
(-1350 2300);
DISPLAY 1.021277 (-1350 2300);
PAINT ORANGE (-1350 2300);
DISPLAY INVISIBLE (-1350 2300);
FORCEADD P3V3_STBY..1
(-3475 4200);
FORCEPROP 3 LASTPIN (-3475 4150) SIG_NAME P3V3_STBY\g
J 0
(-3465 4160);
DISPLAY 0.659574 (-3465 4160);
PAINT MONO (-3465 4160);
DISPLAY INVISIBLE (-3465 4160);
FORCEPROP 1 LAST VOLTAGE 3.3V
J 0
(-3520 4157);
DISPLAY 0.340426 (-3520 4157);
PAINT SKYBLUE (-3520 4157);
DISPLAY INVISIBLE (-3520 4157);
FORCEPROP 2 LAST CDS_LIB mstr_symbols
J 0
(-3475 4200);
PAINT ORANGE (-3475 4200);
DISPLAY INVISIBLE (-3475 4200);
FORCEPROP 1 LAST SIZE 1B
J 0
(-3430 4222);
DISPLAY 0.340426 (-3430 4222);
PAINT GREEN (-3430 4222);
DISPLAY INVISIBLE (-3430 4222);
FORCEPROP 1 LAST BODY_TYPE PLUMBING
J 0
(-3520 4157);
DISPLAY 0.340426 (-3520 4157);
PAINT GREEN (-3520 4157);
DISPLAY INVISIBLE (-3520 4157);
FORCEPROP 1 LAST PATH I116
J 0
(-3430 4202);
DISPLAY 0.340426 (-3430 4202);
PAINT GREEN (-3430 4202);
DISPLAY INVISIBLE (-3430 4202);
FORCEPROP 1 LAST HDL_POWER P3V3_STBY
J 0
(-3775 4075);
DISPLAY 0.872340 (-3775 4075);
PAINT ORANGE (-3775 4075);
DISPLAY INVISIBLE (-3775 4075);
FORCEADD OFFPAGE..2
(1425 2225);
FORCEPROP 2 LAST $XR2 145 
J 0
(1734 2225);
DISPLAY 0.638298 (1734 2225);
PAINT MONO (1734 2225);
FORCEPROP 2 LAST $XR0 133 
J 0
(1614 2225);
DISPLAY 0.638298 (1614 2225);
PAINT MONO (1614 2225);
FORCEPROP 2 LAST $XR1 121 
J 0
(1734 2225);
DISPLAY 0.638298 (1734 2225);
PAINT MONO (1734 2225);
FORCEPROP 2 LAST CDS_LIB mstr_standard
J 0
(1425 2225);
PAINT ORANGE (1425 2225);
DISPLAY INVISIBLE (1425 2225);
FORCEPROP 2 LAST BOM_COST SB
J 0
(1175 2275);
DISPLAY 1.361702 (1175 2275);
PAINT ORANGE (1175 2275);
DISPLAY INVISIBLE (1175 2275);
FORCEPROP 2 LAST ROOM SB
J 0
(1175 2275);
DISPLAY 1.361702 (1175 2275);
PAINT ORANGE (1175 2275);
DISPLAY INVISIBLE (1175 2275);
FORCEPROP 1 LAST OFFPAGE TRUE
J 0
(1750 2100);
DISPLAY 0.872340 (1750 2100);
PAINT GREEN (1750 2100);
DISPLAY INVISIBLE (1750 2100);
FORCEPROP 1 LAST COMMENT_BODY TRUE
J 0
(1380 2130);
DISPLAY 0.872340 (1380 2130);
PAINT GREEN (1380 2130);
DISPLAY INVISIBLE (1380 2130);
FORCEPROP 2 LAST PATH I117
J 0
(1600 2300);
DISPLAY 1.021277 (1600 2300);
PAINT ORANGE (1600 2300);
DISPLAY INVISIBLE (1600 2300);
FORCEADD OFFPAGE..2
(1400 2825);
FORCEPROP 2 LAST $XR0 188 
J 0
(1589 2825);
DISPLAY 0.638298 (1589 2825);
PAINT MONO (1589 2825);
FORCEPROP 2 LAST BOM_COST SB
J 0
(1150 2875);
DISPLAY 1.361702 (1150 2875);
PAINT ORANGE (1150 2875);
DISPLAY INVISIBLE (1150 2875);
FORCEPROP 2 LAST ROOM SB
J 0
(1150 2875);
DISPLAY 1.361702 (1150 2875);
PAINT ORANGE (1150 2875);
DISPLAY INVISIBLE (1150 2875);
FORCEPROP 2 LAST CDS_LIB mstr_standard
J 0
(1400 2825);
PAINT ORANGE (1400 2825);
DISPLAY INVISIBLE (1400 2825);
FORCEPROP 1 LAST OFFPAGE TRUE
J 0
(1725 2700);
DISPLAY 0.872340 (1725 2700);
PAINT GREEN (1725 2700);
DISPLAY INVISIBLE (1725 2700);
FORCEPROP 1 LAST COMMENT_BODY TRUE
J 0
(1355 2730);
DISPLAY 0.872340 (1355 2730);
PAINT GREEN (1355 2730);
DISPLAY INVISIBLE (1355 2730);
FORCEPROP 2 LAST PATH I13
J 0
(1600 2875);
DISPLAY 1.021277 (1600 2875);
PAINT ORANGE (1600 2875);
DISPLAY INVISIBLE (1600 2875);
FORCEADD OFFPAGE..2
(1400 2775);
FORCEPROP 2 LAST $XR0 188 
J 0
(1589 2775);
DISPLAY 0.638298 (1589 2775);
PAINT MONO (1589 2775);
FORCEPROP 2 LAST BOM_COST SB
J 0
(1150 2825);
DISPLAY 1.361702 (1150 2825);
PAINT ORANGE (1150 2825);
DISPLAY INVISIBLE (1150 2825);
FORCEPROP 2 LAST ROOM SB
J 0
(1150 2825);
DISPLAY 1.361702 (1150 2825);
PAINT ORANGE (1150 2825);
DISPLAY INVISIBLE (1150 2825);
FORCEPROP 2 LAST CDS_LIB mstr_standard
J 0
(1400 2775);
PAINT ORANGE (1400 2775);
DISPLAY INVISIBLE (1400 2775);
FORCEPROP 1 LAST OFFPAGE TRUE
J 0
(1725 2650);
DISPLAY 0.872340 (1725 2650);
PAINT GREEN (1725 2650);
DISPLAY INVISIBLE (1725 2650);
FORCEPROP 1 LAST COMMENT_BODY TRUE
J 0
(1355 2680);
DISPLAY 0.872340 (1355 2680);
PAINT GREEN (1355 2680);
DISPLAY INVISIBLE (1355 2680);
FORCEPROP 2 LAST PATH I14
J 0
(1600 2825);
DISPLAY 1.021277 (1600 2825);
PAINT ORANGE (1600 2825);
DISPLAY INVISIBLE (1600 2825);
FORCEADD OFFPAGE..4
(1400 2675);
FORCEPROP 2 LAST $XR0 120 
J 0
(1586 2675);
DISPLAY 0.638298 (1586 2675);
PAINT MONO (1586 2675);
FORCEPROP 2 LAST BOM_COST SB
J 0
(1150 2725);
DISPLAY 1.361702 (1150 2725);
PAINT ORANGE (1150 2725);
DISPLAY INVISIBLE (1150 2725);
FORCEPROP 2 LAST ROOM SB
J 0
(1150 2725);
DISPLAY 1.361702 (1150 2725);
PAINT ORANGE (1150 2725);
DISPLAY INVISIBLE (1150 2725);
FORCEPROP 2 LAST CDS_LIB mstr_standard
J 0
(1400 2675);
PAINT ORANGE (1400 2675);
DISPLAY INVISIBLE (1400 2675);
FORCEPROP 1 LAST OFFPAGE TRUE
J 0
(1725 2550);
DISPLAY 0.872340 (1725 2550);
PAINT GREEN (1725 2550);
DISPLAY INVISIBLE (1725 2550);
FORCEPROP 1 LAST COMMENT_BODY TRUE
J 0
(1375 2575);
DISPLAY 0.872340 (1375 2575);
PAINT GREEN (1375 2575);
DISPLAY INVISIBLE (1375 2575);
FORCEPROP 2 LAST PATH I15
J 0
(1750 2725);
DISPLAY 1.021277 (1750 2725);
PAINT ORANGE (1750 2725);
DISPLAY INVISIBLE (1750 2725);
FORCEADD OFFPAGE..4
(1400 2625);
FORCEPROP 2 LAST $XR0 120 
J 0
(1586 2625);
DISPLAY 0.638298 (1586 2625);
PAINT MONO (1586 2625);
FORCEPROP 2 LAST BOM_COST SB
J 0
(1150 2675);
DISPLAY 1.361702 (1150 2675);
PAINT ORANGE (1150 2675);
DISPLAY INVISIBLE (1150 2675);
FORCEPROP 2 LAST ROOM SB
J 0
(1150 2675);
DISPLAY 1.361702 (1150 2675);
PAINT ORANGE (1150 2675);
DISPLAY INVISIBLE (1150 2675);
FORCEPROP 2 LAST CDS_LIB mstr_standard
J 0
(1400 2625);
PAINT ORANGE (1400 2625);
DISPLAY INVISIBLE (1400 2625);
FORCEPROP 1 LAST OFFPAGE TRUE
J 0
(1725 2500);
DISPLAY 0.872340 (1725 2500);
PAINT GREEN (1725 2500);
DISPLAY INVISIBLE (1725 2500);
FORCEPROP 1 LAST COMMENT_BODY TRUE
J 0
(1375 2525);
DISPLAY 0.872340 (1375 2525);
PAINT GREEN (1375 2525);
DISPLAY INVISIBLE (1375 2525);
FORCEPROP 2 LAST PATH I16
J 0
(1600 2675);
DISPLAY 1.021277 (1600 2675);
PAINT ORANGE (1600 2675);
DISPLAY INVISIBLE (1600 2675);
FORCEADD OFFPAGE..2
(1400 2525);
FORCEPROP 2 LAST $XR0 188 
J 0
(1589 2525);
DISPLAY 0.638298 (1589 2525);
PAINT MONO (1589 2525);
FORCEPROP 2 LAST BOM_COST SB
J 0
(1150 2575);
DISPLAY 1.361702 (1150 2575);
PAINT ORANGE (1150 2575);
DISPLAY INVISIBLE (1150 2575);
FORCEPROP 2 LAST ROOM SB
J 0
(1150 2575);
DISPLAY 1.361702 (1150 2575);
PAINT ORANGE (1150 2575);
DISPLAY INVISIBLE (1150 2575);
FORCEPROP 2 LAST CDS_LIB mstr_standard
J 0
(1400 2525);
PAINT ORANGE (1400 2525);
DISPLAY INVISIBLE (1400 2525);
FORCEPROP 1 LAST OFFPAGE TRUE
J 0
(1725 2400);
DISPLAY 0.872340 (1725 2400);
PAINT GREEN (1725 2400);
DISPLAY INVISIBLE (1725 2400);
FORCEPROP 1 LAST COMMENT_BODY TRUE
J 0
(1355 2430);
DISPLAY 0.872340 (1355 2430);
PAINT GREEN (1355 2430);
DISPLAY INVISIBLE (1355 2430);
FORCEPROP 2 LAST PATH I17
J 0
(1600 2575);
DISPLAY 1.021277 (1600 2575);
PAINT ORANGE (1600 2575);
DISPLAY INVISIBLE (1600 2575);
FORCEADD OFFPAGE..2
(1400 2475);
FORCEPROP 2 LAST $XR0 188 
J 0
(1589 2475);
DISPLAY 0.638298 (1589 2475);
PAINT MONO (1589 2475);
FORCEPROP 2 LAST BOM_COST SB
J 0
(1150 2525);
DISPLAY 1.361702 (1150 2525);
PAINT ORANGE (1150 2525);
DISPLAY INVISIBLE (1150 2525);
FORCEPROP 2 LAST ROOM SB
J 0
(1150 2525);
DISPLAY 1.361702 (1150 2525);
PAINT ORANGE (1150 2525);
DISPLAY INVISIBLE (1150 2525);
FORCEPROP 2 LAST CDS_LIB mstr_standard
J 0
(1400 2475);
PAINT ORANGE (1400 2475);
DISPLAY INVISIBLE (1400 2475);
FORCEPROP 1 LAST OFFPAGE TRUE
J 0
(1725 2350);
DISPLAY 0.872340 (1725 2350);
PAINT GREEN (1725 2350);
DISPLAY INVISIBLE (1725 2350);
FORCEPROP 1 LAST COMMENT_BODY TRUE
J 0
(1355 2380);
DISPLAY 0.872340 (1355 2380);
PAINT GREEN (1355 2380);
DISPLAY INVISIBLE (1355 2380);
FORCEPROP 2 LAST PATH I18
J 0
(1600 2525);
DISPLAY 1.021277 (1600 2525);
PAINT ORANGE (1600 2525);
DISPLAY INVISIBLE (1600 2525);
FORCEADD CAP_A..1
(3300 1275);
FORCEPROP 1 LAST LOCATION C2R15
J 0
(3350 1375);
DISPLAY 0.617021 (3350 1375);
PAINT AQUA (3350 1375);
FORCEPROP 1 LAST PART_NUMBER A36096-030
J 0
(3350 1125);
DISPLAY 0.617021 (3350 1125);
PAINT BLUE (3350 1125);
FORCEPROP 1 LAST VALUE 0.1UF
J 0
(3350 1325);
DISPLAY 0.617021 (3350 1325);
PAINT SKYBLUE (3350 1325);
FORCEPROP 1 LAST TOLERANCE 10%
J 0
(3350 1225);
DISPLAY 0.617021 (3350 1225);
PAINT SKYBLUE (3350 1225);
FORCEPROP 1 LAST PACK_TYPE 0402V
J 0
(3350 1075);
DISPLAY 0.617021 (3350 1075);
PAINT SKYBLUE (3350 1075);
FORCEPROP 1 LAST VOLTAGE 16V
J 0
(3350 1275);
DISPLAY 0.617021 (3350 1275);
PAINT SKYBLUE (3350 1275);
FORCEPROP 1 LAST MATERIAL X7R
J 0
(3350 1175);
DISPLAY 0.617021 (3350 1175);
PAINT SKYBLUE (3350 1175);
FORCEPROP 1 LASTPIN (3300 1375) $PN 1
J 0
(3310 1355);
DISPLAY 0.617021 (3310 1355);
PAINT WHITE (3310 1355);
FORCEPROP 1 LASTPIN (3300 1175) $PN 2
J 0
(3310 1155);
DISPLAY 0.617021 (3310 1155);
PAINT WHITE (3310 1155);
FORCEPROP 1 LAST PATH I2
J 0
(3350 1425);
DISPLAY 0.978723 (3350 1425);
PAINT WHITE (3350 1425);
DISPLAY INVISIBLE (3350 1425);
FORCEPROP 2 LAST ROOM IO_MODULE
J 1
(3350 1425);
DISPLAY 0.744681 (3350 1425);
PAINT ORANGE (3350 1425);
DISPLAY INVISIBLE (3350 1425);
FORCEPROP 2 LAST BOM_COST IO_MODULE
J 0
(3300 1275);
DISPLAY 0.744681 (3300 1275);
PAINT MONO (3300 1275);
DISPLAY INVISIBLE (3300 1275);
FORCEPROP 2 LAST CDS_LIB dev_discrete
J 0
(3300 1275);
PAINT ORANGE (3300 1275);
DISPLAY INVISIBLE (3300 1275);
FORCEPROP 2 LAST CDS_SEC 1
J 0
(3350 1425);
PAINT ORANGE (3350 1425);
DISPLAY INVISIBLE (3350 1425);
FORCEPROP 2 LAST SEC_TYPE 0402V
J 0
(3350 1475);
DISPLAY 1.021277 (3350 1475);
PAINT ORANGE (3350 1475);
DISPLAY INVISIBLE (3350 1475);
FORCEPROP 2 LAST SEC 1
J 0
(3350 1425);
DISPLAY 0.680851 (3350 1425);
PAINT MONO (3350 1425);
DISPLAY INVISIBLE (3350 1425);
FORCEADD CAP_A..1
(2400 1300);
FORCEPROP 1 LAST LOCATION C2P11
J 0
(2450 1400);
DISPLAY 0.617021 (2450 1400);
PAINT AQUA (2450 1400);
FORCEPROP 1 LAST PART_NUMBER A36096-030
J 0
(2450 1150);
DISPLAY 0.617021 (2450 1150);
PAINT BLUE (2450 1150);
FORCEPROP 1 LAST VALUE 0.1UF
J 0
(2450 1350);
DISPLAY 0.617021 (2450 1350);
PAINT SKYBLUE (2450 1350);
FORCEPROP 1 LAST TOLERANCE 10%
J 0
(2450 1250);
DISPLAY 0.617021 (2450 1250);
PAINT SKYBLUE (2450 1250);
FORCEPROP 1 LAST PACK_TYPE 0402V
J 0
(2450 1100);
DISPLAY 0.617021 (2450 1100);
PAINT SKYBLUE (2450 1100);
FORCEPROP 1 LAST VOLTAGE 16V
J 0
(2450 1300);
DISPLAY 0.617021 (2450 1300);
PAINT SKYBLUE (2450 1300);
FORCEPROP 1 LAST MATERIAL X7R
J 0
(2450 1200);
DISPLAY 0.617021 (2450 1200);
PAINT SKYBLUE (2450 1200);
FORCEPROP 1 LASTPIN (2400 1400) $PN 1
J 0
(2410 1380);
DISPLAY 0.617021 (2410 1380);
PAINT WHITE (2410 1380);
FORCEPROP 1 LASTPIN (2400 1200) $PN 2
J 0
(2410 1180);
DISPLAY 0.617021 (2410 1180);
PAINT WHITE (2410 1180);
FORCEPROP 1 LAST PATH I21
J 0
(2450 1450);
DISPLAY 0.978723 (2450 1450);
PAINT WHITE (2450 1450);
DISPLAY INVISIBLE (2450 1450);
FORCEPROP 2 LAST ROOM IO_MODULE
J 1
(2450 1450);
DISPLAY 0.744681 (2450 1450);
PAINT ORANGE (2450 1450);
DISPLAY INVISIBLE (2450 1450);
FORCEPROP 2 LAST BOM_COST IO_MODULE
J 0
(2400 1300);
DISPLAY 0.744681 (2400 1300);
PAINT MONO (2400 1300);
DISPLAY INVISIBLE (2400 1300);
FORCEPROP 2 LAST CDS_LIB dev_discrete
J 0
(2400 1300);
PAINT ORANGE (2400 1300);
DISPLAY INVISIBLE (2400 1300);
FORCEPROP 2 LAST CDS_SEC 1
J 0
(2450 1450);
PAINT ORANGE (2450 1450);
DISPLAY INVISIBLE (2450 1450);
FORCEPROP 2 LAST SEC_TYPE 0402V
J 0
(2450 1500);
DISPLAY 1.021277 (2450 1500);
PAINT ORANGE (2450 1500);
DISPLAY INVISIBLE (2450 1500);
FORCEPROP 2 LAST SEC 1
J 0
(2450 1450);
DISPLAY 0.680851 (2450 1450);
PAINT MONO (2450 1450);
DISPLAY INVISIBLE (2450 1450);
FORCEADD CAP_A..1
(2050 1300);
FORCEPROP 1 LAST LOCATION C2P12
J 0
(2100 1400);
DISPLAY 0.617021 (2100 1400);
PAINT AQUA (2100 1400);
FORCEPROP 1 LAST PART_NUMBER A36096-030
J 0
(2100 1150);
DISPLAY 0.617021 (2100 1150);
PAINT BLUE (2100 1150);
FORCEPROP 1 LAST VALUE 0.1UF
J 0
(2100 1350);
DISPLAY 0.617021 (2100 1350);
PAINT SKYBLUE (2100 1350);
FORCEPROP 1 LAST TOLERANCE 10%
J 0
(2100 1250);
DISPLAY 0.617021 (2100 1250);
PAINT SKYBLUE (2100 1250);
FORCEPROP 1 LAST PACK_TYPE 0402V
J 0
(2100 1100);
DISPLAY 0.617021 (2100 1100);
PAINT SKYBLUE (2100 1100);
FORCEPROP 1 LAST VOLTAGE 16V
J 0
(2100 1300);
DISPLAY 0.617021 (2100 1300);
PAINT SKYBLUE (2100 1300);
FORCEPROP 1 LAST MATERIAL X7R
J 0
(2100 1200);
DISPLAY 0.617021 (2100 1200);
PAINT SKYBLUE (2100 1200);
FORCEPROP 1 LASTPIN (2050 1400) $PN 1
J 0
(2060 1380);
DISPLAY 0.617021 (2060 1380);
PAINT WHITE (2060 1380);
FORCEPROP 1 LASTPIN (2050 1200) $PN 2
J 0
(2060 1180);
DISPLAY 0.617021 (2060 1180);
PAINT WHITE (2060 1180);
FORCEPROP 1 LAST PATH I23
J 0
(2100 1450);
DISPLAY 0.978723 (2100 1450);
PAINT WHITE (2100 1450);
DISPLAY INVISIBLE (2100 1450);
FORCEPROP 2 LAST ROOM IO_MODULE
J 1
(2100 1450);
DISPLAY 0.744681 (2100 1450);
PAINT ORANGE (2100 1450);
DISPLAY INVISIBLE (2100 1450);
FORCEPROP 2 LAST BOM_COST IO_MODULE
J 0
(2050 1300);
DISPLAY 0.744681 (2050 1300);
PAINT MONO (2050 1300);
DISPLAY INVISIBLE (2050 1300);
FORCEPROP 2 LAST CDS_LIB dev_discrete
J 0
(2050 1300);
PAINT ORANGE (2050 1300);
DISPLAY INVISIBLE (2050 1300);
FORCEPROP 2 LAST CDS_SEC 1
J 0
(2100 1450);
PAINT ORANGE (2100 1450);
DISPLAY INVISIBLE (2100 1450);
FORCEPROP 2 LAST SEC_TYPE 0402V
J 0
(2100 1500);
DISPLAY 1.021277 (2100 1500);
PAINT ORANGE (2100 1500);
DISPLAY INVISIBLE (2100 1500);
FORCEPROP 2 LAST SEC 1
J 0
(2100 1500);
DISPLAY 0.680851 (2100 1500);
PAINT MONO (2100 1500);
DISPLAY INVISIBLE (2100 1500);
FORCEADD GND..1
(650 2000);
FORCEPROP 3 LASTPIN (650 2050) SIG_NAME GND\g
J 0
(660 2060);
DISPLAY 0.659574 (660 2060);
PAINT MONO (660 2060);
DISPLAY INVISIBLE (660 2060);
FORCEPROP 1 LAST VOLTAGE 0
J 0
(625 2075);
DISPLAY 1.021277 (625 2075);
PAINT SKYBLUE (625 2075);
DISPLAY INVISIBLE (625 2075);
FORCEPROP 1 LAST SIZE 1B
J 0
(725 1950);
DISPLAY 0.872340 (725 1950);
PAINT GREEN (725 1950);
DISPLAY INVISIBLE (725 1950);
FORCEPROP 2 LAST CDS_LIB mstr_symbols
J 0
(650 2000);
PAINT ORANGE (650 2000);
DISPLAY INVISIBLE (650 2000);
FORCEPROP 1 LAST BODY_TYPE PLUMBING
J 0
(605 1957);
DISPLAY 0.340426 (605 1957);
PAINT GREEN (605 1957);
DISPLAY INVISIBLE (605 1957);
FORCEPROP 1 LAST PATH I24
J 0
(725 2000);
DISPLAY 0.872340 (725 2000);
PAINT AQUA (725 2000);
DISPLAY INVISIBLE (725 2000);
FORCEPROP 1 LAST HDL_POWER GND
J 0
(650 2150);
DISPLAY 0.872340 (650 2150);
PAINT GREEN (650 2150);
DISPLAY INVISIBLE (650 2150);
FORCEADD CAP_A..1
(1000 1300);
FORCEPROP 1 LAST LOCATION C2R17
J 0
(1050 1400);
DISPLAY 0.617021 (1050 1400);
PAINT AQUA (1050 1400);
FORCEPROP 1 LAST PART_NUMBER A36096-030
J 0
(1050 1150);
DISPLAY 0.617021 (1050 1150);
PAINT BLUE (1050 1150);
FORCEPROP 1 LAST VALUE 0.1UF
J 0
(1050 1350);
DISPLAY 0.617021 (1050 1350);
PAINT SKYBLUE (1050 1350);
FORCEPROP 1 LAST TOLERANCE 10%
J 0
(1050 1250);
DISPLAY 0.617021 (1050 1250);
PAINT SKYBLUE (1050 1250);
FORCEPROP 1 LAST PACK_TYPE 0402V
J 0
(1050 1100);
DISPLAY 0.617021 (1050 1100);
PAINT SKYBLUE (1050 1100);
FORCEPROP 1 LAST VOLTAGE 16V
J 0
(1050 1300);
DISPLAY 0.617021 (1050 1300);
PAINT SKYBLUE (1050 1300);
FORCEPROP 1 LAST MATERIAL X7R
J 0
(1050 1200);
DISPLAY 0.617021 (1050 1200);
PAINT SKYBLUE (1050 1200);
FORCEPROP 1 LASTPIN (1000 1400) $PN 1
J 0
(1010 1380);
DISPLAY 0.617021 (1010 1380);
PAINT WHITE (1010 1380);
FORCEPROP 1 LASTPIN (1000 1200) $PN 2
J 0
(1010 1180);
DISPLAY 0.617021 (1010 1180);
PAINT WHITE (1010 1180);
FORCEPROP 1 LAST PATH I25
J 0
(1050 1450);
DISPLAY 0.978723 (1050 1450);
PAINT WHITE (1050 1450);
DISPLAY INVISIBLE (1050 1450);
FORCEPROP 2 LAST ROOM IO_MODULE
J 1
(1050 1450);
DISPLAY 0.744681 (1050 1450);
PAINT ORANGE (1050 1450);
DISPLAY INVISIBLE (1050 1450);
FORCEPROP 2 LAST BOM_COST IO_MODULE
J 0
(1000 1300);
DISPLAY 0.744681 (1000 1300);
PAINT MONO (1000 1300);
DISPLAY INVISIBLE (1000 1300);
FORCEPROP 2 LAST CDS_LIB dev_discrete
J 0
(1000 1300);
PAINT ORANGE (1000 1300);
DISPLAY INVISIBLE (1000 1300);
FORCEPROP 2 LAST CDS_SEC 1
J 1
(1050 1500);
DISPLAY 0.744681 (1050 1500);
PAINT MONO (1050 1500);
DISPLAY INVISIBLE (1050 1500);
FORCEPROP 2 LAST $SEC 1
J 1
(1050 1500);
DISPLAY 0.744681 (1050 1500);
PAINT MONO (1050 1500);
DISPLAY INVISIBLE (1050 1500);
FORCEADD SCONN64_H87568002_A..1
(150 3025);
FORCEPROP 1 LAST LOCATION J8E4
J 0
(-100 4075);
DISPLAY 0.617021 (-100 4075);
PAINT AQUA (-100 4075);
FORCEPROP 1 LAST PART_NUMBER H87568-002
J 0
(-100 2075);
DISPLAY 0.617021 (-100 2075);
PAINT BLUE (-100 2075);
FORCEPROP 1 LAST MATERIAL CONN
J 0
(-100 4025);
DISPLAY 0.617021 (-100 4025);
PAINT SKYBLUE (-100 4025);
FORCEPROP 2 LASTPIN (450 2225) $PN 64
J 0
(460 2235);
DISPLAY 0.617021 (460 2235);
PAINT ORANGE (460 2235);
FORCEPROP 2 LASTPIN (450 2275) $PN 63
J 0
(460 2285);
DISPLAY 0.617021 (460 2285);
PAINT ORANGE (460 2285);
FORCEPROP 2 LASTPIN (450 2325) $PN 62
J 0
(460 2335);
DISPLAY 0.617021 (460 2335);
PAINT ORANGE (460 2335);
FORCEPROP 2 LASTPIN (450 2375) $PN 61
J 0
(460 2385);
DISPLAY 0.617021 (460 2385);
PAINT ORANGE (460 2385);
FORCEPROP 2 LASTPIN (450 2425) $PN 60
J 0
(460 2435);
DISPLAY 0.617021 (460 2435);
PAINT ORANGE (460 2435);
FORCEPROP 2 LASTPIN (450 2475) $PN 59
J 0
(460 2485);
DISPLAY 0.617021 (460 2485);
PAINT ORANGE (460 2485);
FORCEPROP 2 LASTPIN (450 2525) $PN 58
J 0
(460 2535);
DISPLAY 0.617021 (460 2535);
PAINT ORANGE (460 2535);
FORCEPROP 2 LASTPIN (450 2575) $PN 57
J 0
(460 2585);
DISPLAY 0.617021 (460 2585);
PAINT ORANGE (460 2585);
FORCEPROP 2 LASTPIN (450 2625) $PN 56
J 0
(460 2635);
DISPLAY 0.617021 (460 2635);
PAINT ORANGE (460 2635);
FORCEPROP 2 LASTPIN (450 2675) $PN 55
J 0
(460 2685);
DISPLAY 0.617021 (460 2685);
PAINT ORANGE (460 2685);
FORCEPROP 2 LASTPIN (450 2725) $PN 54
J 0
(460 2735);
DISPLAY 0.617021 (460 2735);
PAINT ORANGE (460 2735);
FORCEPROP 2 LASTPIN (450 2775) $PN 53
J 0
(460 2785);
DISPLAY 0.617021 (460 2785);
PAINT ORANGE (460 2785);
FORCEPROP 2 LASTPIN (450 2825) $PN 52
J 0
(460 2835);
DISPLAY 0.617021 (460 2835);
PAINT ORANGE (460 2835);
FORCEPROP 2 LASTPIN (450 2875) $PN 51
J 0
(460 2885);
DISPLAY 0.617021 (460 2885);
PAINT ORANGE (460 2885);
FORCEPROP 2 LASTPIN (450 2925) $PN 50
J 0
(460 2935);
DISPLAY 0.617021 (460 2935);
PAINT ORANGE (460 2935);
FORCEPROP 2 LASTPIN (450 2975) $PN 49
J 0
(460 2985);
DISPLAY 0.617021 (460 2985);
PAINT ORANGE (460 2985);
FORCEPROP 2 LASTPIN (450 3025) $PN 48
J 0
(460 3035);
DISPLAY 0.617021 (460 3035);
PAINT ORANGE (460 3035);
FORCEPROP 2 LASTPIN (450 3075) $PN 47
J 0
(460 3085);
DISPLAY 0.617021 (460 3085);
PAINT ORANGE (460 3085);
FORCEPROP 2 LASTPIN (450 3125) $PN 46
J 0
(460 3135);
DISPLAY 0.617021 (460 3135);
PAINT ORANGE (460 3135);
FORCEPROP 2 LASTPIN (450 3175) $PN 45
J 0
(460 3185);
DISPLAY 0.617021 (460 3185);
PAINT ORANGE (460 3185);
FORCEPROP 2 LASTPIN (450 3225) $PN 44
J 0
(460 3235);
DISPLAY 0.617021 (460 3235);
PAINT ORANGE (460 3235);
FORCEPROP 2 LASTPIN (450 3275) $PN 43
J 0
(460 3285);
DISPLAY 0.617021 (460 3285);
PAINT ORANGE (460 3285);
FORCEPROP 2 LASTPIN (450 3325) $PN 42
J 0
(460 3335);
DISPLAY 0.617021 (460 3335);
PAINT ORANGE (460 3335);
FORCEPROP 2 LASTPIN (450 3375) $PN 41
J 0
(460 3385);
DISPLAY 0.617021 (460 3385);
PAINT ORANGE (460 3385);
FORCEPROP 2 LASTPIN (450 3425) $PN 40
J 0
(460 3435);
DISPLAY 0.617021 (460 3435);
PAINT ORANGE (460 3435);
FORCEPROP 2 LASTPIN (450 3475) $PN 39
J 0
(460 3485);
DISPLAY 0.617021 (460 3485);
PAINT ORANGE (460 3485);
FORCEPROP 2 LASTPIN (450 3525) $PN 38
J 0
(460 3535);
DISPLAY 0.617021 (460 3535);
PAINT ORANGE (460 3535);
FORCEPROP 2 LASTPIN (450 3575) $PN 37
J 0
(460 3585);
DISPLAY 0.617021 (460 3585);
PAINT ORANGE (460 3585);
FORCEPROP 2 LASTPIN (450 3625) $PN 36
J 0
(460 3635);
DISPLAY 0.617021 (460 3635);
PAINT ORANGE (460 3635);
FORCEPROP 2 LASTPIN (450 3675) $PN 35
J 0
(460 3685);
DISPLAY 0.617021 (460 3685);
PAINT ORANGE (460 3685);
FORCEPROP 2 LASTPIN (450 3725) $PN 34
J 0
(460 3735);
DISPLAY 0.617021 (460 3735);
PAINT ORANGE (460 3735);
FORCEPROP 2 LASTPIN (450 3775) $PN 33
J 0
(460 3785);
DISPLAY 0.617021 (460 3785);
PAINT ORANGE (460 3785);
FORCEPROP 2 LASTPIN (-150 2225) $PN 32
J 2
(-160 2235);
DISPLAY 0.617021 (-160 2235);
PAINT ORANGE (-160 2235);
FORCEPROP 2 LASTPIN (-150 2275) $PN 31
J 2
(-160 2285);
DISPLAY 0.617021 (-160 2285);
PAINT ORANGE (-160 2285);
FORCEPROP 2 LASTPIN (-150 2325) $PN 30
J 2
(-160 2335);
DISPLAY 0.617021 (-160 2335);
PAINT ORANGE (-160 2335);
FORCEPROP 2 LASTPIN (-150 2375) $PN 29
J 2
(-160 2385);
DISPLAY 0.617021 (-160 2385);
PAINT ORANGE (-160 2385);
FORCEPROP 2 LASTPIN (-150 2425) $PN 28
J 2
(-160 2435);
DISPLAY 0.617021 (-160 2435);
PAINT ORANGE (-160 2435);
FORCEPROP 2 LASTPIN (-150 2475) $PN 27
J 2
(-160 2485);
DISPLAY 0.617021 (-160 2485);
PAINT ORANGE (-160 2485);
FORCEPROP 2 LASTPIN (-150 2525) $PN 26
J 2
(-160 2535);
DISPLAY 0.617021 (-160 2535);
PAINT ORANGE (-160 2535);
FORCEPROP 2 LASTPIN (-150 2575) $PN 25
J 2
(-160 2585);
DISPLAY 0.617021 (-160 2585);
PAINT ORANGE (-160 2585);
FORCEPROP 2 LASTPIN (-150 2625) $PN 24
J 2
(-160 2635);
DISPLAY 0.617021 (-160 2635);
PAINT ORANGE (-160 2635);
FORCEPROP 2 LASTPIN (-150 2675) $PN 23
J 2
(-160 2685);
DISPLAY 0.617021 (-160 2685);
PAINT ORANGE (-160 2685);
FORCEPROP 2 LASTPIN (-150 2725) $PN 22
J 2
(-160 2735);
DISPLAY 0.617021 (-160 2735);
PAINT ORANGE (-160 2735);
FORCEPROP 2 LASTPIN (-150 2775) $PN 21
J 2
(-160 2785);
DISPLAY 0.617021 (-160 2785);
PAINT ORANGE (-160 2785);
FORCEPROP 2 LASTPIN (-150 2825) $PN 20
J 2
(-160 2835);
DISPLAY 0.617021 (-160 2835);
PAINT ORANGE (-160 2835);
FORCEPROP 2 LASTPIN (-150 2875) $PN 19
J 2
(-160 2885);
DISPLAY 0.617021 (-160 2885);
PAINT ORANGE (-160 2885);
FORCEPROP 2 LASTPIN (-150 2925) $PN 18
J 2
(-160 2935);
DISPLAY 0.617021 (-160 2935);
PAINT ORANGE (-160 2935);
FORCEPROP 2 LASTPIN (-150 2975) $PN 17
J 2
(-160 2985);
DISPLAY 0.617021 (-160 2985);
PAINT ORANGE (-160 2985);
FORCEPROP 2 LASTPIN (-150 3025) $PN 16
J 2
(-160 3035);
DISPLAY 0.617021 (-160 3035);
PAINT ORANGE (-160 3035);
FORCEPROP 2 LASTPIN (-150 3075) $PN 15
J 2
(-160 3085);
DISPLAY 0.617021 (-160 3085);
PAINT ORANGE (-160 3085);
FORCEPROP 2 LASTPIN (-150 3125) $PN 14
J 2
(-160 3135);
DISPLAY 0.617021 (-160 3135);
PAINT ORANGE (-160 3135);
FORCEPROP 2 LASTPIN (-150 3175) $PN 13
J 2
(-160 3185);
DISPLAY 0.617021 (-160 3185);
PAINT ORANGE (-160 3185);
FORCEPROP 2 LASTPIN (-150 3225) $PN 12
J 2
(-160 3235);
DISPLAY 0.617021 (-160 3235);
PAINT ORANGE (-160 3235);
FORCEPROP 2 LASTPIN (-150 3275) $PN 11
J 2
(-160 3285);
DISPLAY 0.617021 (-160 3285);
PAINT ORANGE (-160 3285);
FORCEPROP 2 LASTPIN (-150 3325) $PN 10
J 2
(-160 3335);
DISPLAY 0.617021 (-160 3335);
PAINT ORANGE (-160 3335);
FORCEPROP 2 LASTPIN (-150 3375) $PN 9
J 2
(-160 3385);
DISPLAY 0.617021 (-160 3385);
PAINT ORANGE (-160 3385);
FORCEPROP 2 LASTPIN (-150 3425) $PN 8
J 2
(-160 3435);
DISPLAY 0.617021 (-160 3435);
PAINT ORANGE (-160 3435);
FORCEPROP 2 LASTPIN (-150 3475) $PN 7
J 2
(-160 3485);
DISPLAY 0.617021 (-160 3485);
PAINT ORANGE (-160 3485);
FORCEPROP 2 LASTPIN (-150 3525) $PN 6
J 2
(-160 3535);
DISPLAY 0.617021 (-160 3535);
PAINT ORANGE (-160 3535);
FORCEPROP 2 LASTPIN (-150 3575) $PN 5
J 2
(-160 3585);
DISPLAY 0.617021 (-160 3585);
PAINT ORANGE (-160 3585);
FORCEPROP 2 LASTPIN (-150 3625) $PN 4
J 2
(-160 3635);
DISPLAY 0.617021 (-160 3635);
PAINT ORANGE (-160 3635);
FORCEPROP 2 LASTPIN (-150 3675) $PN 3
J 2
(-160 3685);
DISPLAY 0.617021 (-160 3685);
PAINT ORANGE (-160 3685);
FORCEPROP 2 LASTPIN (-150 3725) $PN 2
J 2
(-160 3735);
DISPLAY 0.617021 (-160 3735);
PAINT ORANGE (-160 3735);
FORCEPROP 2 LASTPIN (-150 3775) $PN 1
J 2
(-160 3785);
DISPLAY 0.617021 (-160 3785);
PAINT ORANGE (-160 3785);
FORCEPROP 1 LAST PACK_TYPE SMT
J 0
(-100 4125);
PAINT SKYBLUE (-100 4125);
DISPLAY INVISIBLE (-100 4125);
FORCEPROP 2 LAST CDS_LIB mstr_sconn
J 0
(150 3025);
PAINT ORANGE (150 3025);
DISPLAY INVISIBLE (150 3025);
FORCEPROP 2 LAST SEC_TYPE SMT
J 0
(-100 4125);
DISPLAY 1.021277 (-100 4125);
PAINT ORANGE (-100 4125);
DISPLAY INVISIBLE (-100 4125);
FORCEPROP 2 LAST SEC 1
J 0
(-100 4125);
DISPLAY 0.680851 (-100 4125);
PAINT MONO (-100 4125);
DISPLAY INVISIBLE (-100 4125);
FORCEPROP 1 LAST PATH I27
J 0
(150 4025);
PAINT GREEN (150 4025);
DISPLAY INVISIBLE (150 4025);
FORCEPROP 0 LAST ROOM IO_MODULE
J 0
(-100 4175);
DISPLAY 1.021277 (-100 4175);
PAINT ORANGE (-100 4175);
DISPLAY INVISIBLE (-100 4175);
FORCEADD OFFPAGE..1
(-1400 3775);
FORCEPROP 2 LAST $XR0 138 
J 0
(-1682 3775);
DISPLAY 0.638298 (-1682 3775);
PAINT MONO (-1682 3775);
FORCEPROP 2 LAST $XR1 159 
J 0
(-1802 3775);
DISPLAY 0.638298 (-1802 3775);
PAINT MONO (-1802 3775);
FORCEPROP 2 LAST $XR2 91 
J 0
(-1892 3775);
DISPLAY 0.638298 (-1892 3775);
PAINT MONO (-1892 3775);
FORCEPROP 2 LAST $XR3 186 
J 0
(-2012 3775);
DISPLAY 0.638298 (-2012 3775);
PAINT MONO (-2012 3775);
FORCEPROP 2 LAST ROOM SB
J 0
(-1650 3825);
DISPLAY 1.361702 (-1650 3825);
PAINT ORANGE (-1650 3825);
DISPLAY INVISIBLE (-1650 3825);
FORCEPROP 2 LAST BOM_COST SB
J 0
(-1650 3825);
DISPLAY 1.361702 (-1650 3825);
PAINT ORANGE (-1650 3825);
DISPLAY INVISIBLE (-1650 3825);
FORCEPROP 2 LAST CDS_LIB mstr_standard
J 0
(-1400 3775);
PAINT ORANGE (-1400 3775);
DISPLAY INVISIBLE (-1400 3775);
FORCEPROP 1 LAST OFFPAGE TRUE
J 0
(-1075 3650);
DISPLAY 0.872340 (-1075 3650);
PAINT GREEN (-1075 3650);
DISPLAY INVISIBLE (-1075 3650);
FORCEPROP 1 LAST COMMENT_BODY TRUE
J 0
(-1275 3675);
DISPLAY 0.872340 (-1275 3675);
PAINT GREEN (-1275 3675);
DISPLAY INVISIBLE (-1275 3675);
FORCEPROP 2 LAST PATH I28
J 0
(-1675 3825);
DISPLAY 1.021277 (-1675 3825);
PAINT ORANGE (-1675 3825);
DISPLAY INVISIBLE (-1675 3825);
FORCEADD OFFPAGE..6
(-1400 3725);
FORCEPROP 2 LAST $XR0 91 
J 0
(-1649 3725);
DISPLAY 0.638298 (-1649 3725);
PAINT MONO (-1649 3725);
FORCEPROP 2 LAST $XR1 138 
J 0
(-1769 3725);
DISPLAY 0.638298 (-1769 3725);
PAINT MONO (-1769 3725);
FORCEPROP 2 LAST $XR2 159 
J 0
(-1889 3725);
DISPLAY 0.638298 (-1889 3725);
PAINT MONO (-1889 3725);
FORCEPROP 2 LAST $XR3 186 
J 0
(-2009 3725);
DISPLAY 0.638298 (-2009 3725);
PAINT MONO (-2009 3725);
FORCEPROP 2 LAST CDS_LIB mstr_standard
J 0
(-1400 3725);
PAINT ORANGE (-1400 3725);
DISPLAY INVISIBLE (-1400 3725);
FORCEPROP 2 LAST BOM_COST SB
J 0
(-1650 3775);
DISPLAY 1.361702 (-1650 3775);
PAINT ORANGE (-1650 3775);
DISPLAY INVISIBLE (-1650 3775);
FORCEPROP 2 LAST ROOM SB
J 0
(-1650 3775);
DISPLAY 1.361702 (-1650 3775);
PAINT ORANGE (-1650 3775);
DISPLAY INVISIBLE (-1650 3775);
FORCEPROP 1 LAST OFFPAGE TRUE
J 0
(-1075 3600);
DISPLAY 0.872340 (-1075 3600);
PAINT GREEN (-1075 3600);
DISPLAY INVISIBLE (-1075 3600);
FORCEPROP 1 LAST COMMENT_BODY TRUE
J 0
(-1300 3650);
DISPLAY 0.872340 (-1300 3650);
PAINT GREEN (-1300 3650);
DISPLAY INVISIBLE (-1300 3650);
FORCEPROP 2 LAST PATH I29
J 0
(-1725 3775);
DISPLAY 1.021277 (-1725 3775);
PAINT ORANGE (-1725 3775);
DISPLAY INVISIBLE (-1725 3775);
FORCEADD CAP_A..1
(2925 1300);
FORCEPROP 1 LAST LOCATION C2R18
J 0
(2975 1400);
DISPLAY 0.617021 (2975 1400);
PAINT AQUA (2975 1400);
FORCEPROP 1 LAST PART_NUMBER A36096-030
J 0
(2975 1150);
DISPLAY 0.617021 (2975 1150);
PAINT BLUE (2975 1150);
FORCEPROP 1 LAST VALUE 0.1UF
J 0
(2975 1350);
DISPLAY 0.617021 (2975 1350);
PAINT SKYBLUE (2975 1350);
FORCEPROP 1 LAST TOLERANCE 10%
J 0
(2975 1250);
DISPLAY 0.617021 (2975 1250);
PAINT SKYBLUE (2975 1250);
FORCEPROP 1 LAST PACK_TYPE 0402V
J 0
(2975 1100);
DISPLAY 0.617021 (2975 1100);
PAINT SKYBLUE (2975 1100);
FORCEPROP 1 LAST VOLTAGE 16V
J 0
(2975 1300);
DISPLAY 0.617021 (2975 1300);
PAINT SKYBLUE (2975 1300);
FORCEPROP 1 LAST MATERIAL X7R
J 0
(2975 1200);
DISPLAY 0.617021 (2975 1200);
PAINT SKYBLUE (2975 1200);
FORCEPROP 1 LASTPIN (2925 1400) $PN 1
J 0
(2935 1380);
DISPLAY 0.617021 (2935 1380);
PAINT WHITE (2935 1380);
FORCEPROP 1 LASTPIN (2925 1200) $PN 2
J 0
(2935 1180);
DISPLAY 0.617021 (2935 1180);
PAINT WHITE (2935 1180);
FORCEPROP 1 LAST PATH I3
J 0
(2975 1450);
DISPLAY 0.978723 (2975 1450);
PAINT WHITE (2975 1450);
DISPLAY INVISIBLE (2975 1450);
FORCEPROP 2 LAST ROOM IO_MODULE
J 1
(2975 1450);
DISPLAY 0.744681 (2975 1450);
PAINT ORANGE (2975 1450);
DISPLAY INVISIBLE (2975 1450);
FORCEPROP 2 LAST BOM_COST IO_MODULE
J 0
(2925 1300);
DISPLAY 0.744681 (2925 1300);
PAINT MONO (2925 1300);
DISPLAY INVISIBLE (2925 1300);
FORCEPROP 2 LAST CDS_LIB dev_discrete
J 0
(2925 1300);
PAINT ORANGE (2925 1300);
DISPLAY INVISIBLE (2925 1300);
FORCEPROP 2 LAST CDS_SEC 1
J 1
(2975 1500);
DISPLAY 0.744681 (2975 1500);
PAINT MONO (2975 1500);
DISPLAY INVISIBLE (2975 1500);
FORCEPROP 2 LAST $SEC 1
J 1
(2975 1500);
DISPLAY 0.744681 (2975 1500);
PAINT MONO (2975 1500);
DISPLAY INVISIBLE (2975 1500);
FORCEADD OFFPAGE..1
(-1400 3575);
FORCEPROP 2 LAST $XR0 118 
J 0
(-1682 3575);
DISPLAY 0.638298 (-1682 3575);
PAINT MONO (-1682 3575);
FORCEPROP 2 LAST CDS_LIB mstr_standard
J 0
(-1400 3575);
PAINT ORANGE (-1400 3575);
DISPLAY INVISIBLE (-1400 3575);
FORCEPROP 2 LAST BOM_COST SB
J 0
(-1650 3625);
DISPLAY 1.361702 (-1650 3625);
PAINT ORANGE (-1650 3625);
DISPLAY INVISIBLE (-1650 3625);
FORCEPROP 2 LAST ROOM SB
J 0
(-1650 3625);
DISPLAY 1.361702 (-1650 3625);
PAINT ORANGE (-1650 3625);
DISPLAY INVISIBLE (-1650 3625);
FORCEPROP 1 LAST OFFPAGE TRUE
J 0
(-1075 3450);
DISPLAY 0.872340 (-1075 3450);
PAINT GREEN (-1075 3450);
DISPLAY INVISIBLE (-1075 3450);
FORCEPROP 1 LAST COMMENT_BODY TRUE
J 0
(-1275 3475);
DISPLAY 0.872340 (-1275 3475);
PAINT GREEN (-1275 3475);
DISPLAY INVISIBLE (-1275 3475);
FORCEPROP 2 LAST PATH I30
J 0
(-1675 3625);
DISPLAY 1.021277 (-1675 3625);
PAINT ORANGE (-1675 3625);
DISPLAY INVISIBLE (-1675 3625);
FORCEADD OFFPAGE..1
(-1400 3525);
FORCEPROP 2 LAST $XR0 118 
J 0
(-1682 3525);
DISPLAY 0.638298 (-1682 3525);
PAINT MONO (-1682 3525);
FORCEPROP 2 LAST CDS_LIB mstr_standard
J 0
(-1400 3525);
PAINT ORANGE (-1400 3525);
DISPLAY INVISIBLE (-1400 3525);
FORCEPROP 2 LAST BOM_COST SB
J 0
(-1650 3575);
DISPLAY 1.361702 (-1650 3575);
PAINT ORANGE (-1650 3575);
DISPLAY INVISIBLE (-1650 3575);
FORCEPROP 2 LAST ROOM SB
J 0
(-1650 3575);
DISPLAY 1.361702 (-1650 3575);
PAINT ORANGE (-1650 3575);
DISPLAY INVISIBLE (-1650 3575);
FORCEPROP 1 LAST OFFPAGE TRUE
J 0
(-1075 3400);
DISPLAY 0.872340 (-1075 3400);
PAINT GREEN (-1075 3400);
DISPLAY INVISIBLE (-1075 3400);
FORCEPROP 1 LAST COMMENT_BODY TRUE
J 0
(-1275 3425);
DISPLAY 0.872340 (-1275 3425);
PAINT GREEN (-1275 3425);
DISPLAY INVISIBLE (-1275 3425);
FORCEPROP 2 LAST PATH I31
J 0
(-1675 3575);
DISPLAY 1.021277 (-1675 3575);
PAINT ORANGE (-1675 3575);
DISPLAY INVISIBLE (-1675 3575);
FORCEADD OFFPAGE..1
(-1400 3425);
FORCEPROP 2 LAST $XR0 120 
J 0
(-1682 3425);
DISPLAY 0.638298 (-1682 3425);
PAINT MONO (-1682 3425);
FORCEPROP 2 LAST CDS_LIB mstr_standard
J 0
(-1400 3425);
PAINT ORANGE (-1400 3425);
DISPLAY INVISIBLE (-1400 3425);
FORCEPROP 2 LAST BOM_COST SB
J 0
(-1650 3475);
DISPLAY 1.361702 (-1650 3475);
PAINT ORANGE (-1650 3475);
DISPLAY INVISIBLE (-1650 3475);
FORCEPROP 2 LAST ROOM SB
J 0
(-1650 3475);
DISPLAY 1.361702 (-1650 3475);
PAINT ORANGE (-1650 3475);
DISPLAY INVISIBLE (-1650 3475);
FORCEPROP 1 LAST OFFPAGE TRUE
J 0
(-1075 3300);
DISPLAY 0.872340 (-1075 3300);
PAINT GREEN (-1075 3300);
DISPLAY INVISIBLE (-1075 3300);
FORCEPROP 1 LAST COMMENT_BODY TRUE
J 0
(-1275 3325);
DISPLAY 0.872340 (-1275 3325);
PAINT GREEN (-1275 3325);
DISPLAY INVISIBLE (-1275 3325);
FORCEPROP 2 LAST PATH I32
J 0
(-1675 3475);
DISPLAY 1.021277 (-1675 3475);
PAINT ORANGE (-1675 3475);
DISPLAY INVISIBLE (-1675 3475);
FORCEADD OFFPAGE..1
(-1400 3375);
FORCEPROP 2 LAST $XR0 120 
J 0
(-1682 3375);
DISPLAY 0.638298 (-1682 3375);
PAINT MONO (-1682 3375);
FORCEPROP 2 LAST CDS_LIB mstr_standard
J 0
(-1400 3375);
PAINT ORANGE (-1400 3375);
DISPLAY INVISIBLE (-1400 3375);
FORCEPROP 2 LAST BOM_COST SB
J 0
(-1650 3425);
DISPLAY 1.361702 (-1650 3425);
PAINT ORANGE (-1650 3425);
DISPLAY INVISIBLE (-1650 3425);
FORCEPROP 2 LAST ROOM SB
J 0
(-1650 3425);
DISPLAY 1.361702 (-1650 3425);
PAINT ORANGE (-1650 3425);
DISPLAY INVISIBLE (-1650 3425);
FORCEPROP 1 LAST OFFPAGE TRUE
J 0
(-1075 3250);
DISPLAY 0.872340 (-1075 3250);
PAINT GREEN (-1075 3250);
DISPLAY INVISIBLE (-1075 3250);
FORCEPROP 1 LAST COMMENT_BODY TRUE
J 0
(-1275 3275);
DISPLAY 0.872340 (-1275 3275);
PAINT GREEN (-1275 3275);
DISPLAY INVISIBLE (-1275 3275);
FORCEPROP 2 LAST PATH I33
J 0
(-1675 3425);
DISPLAY 1.021277 (-1675 3425);
PAINT ORANGE (-1675 3425);
DISPLAY INVISIBLE (-1675 3425);
FORCEADD OFFPAGE..1
(-1400 3275);
FORCEPROP 2 LAST $XR0 118 
J 0
(-1682 3275);
DISPLAY 0.638298 (-1682 3275);
PAINT MONO (-1682 3275);
FORCEPROP 2 LAST CDS_LIB mstr_standard
J 0
(-1400 3275);
PAINT ORANGE (-1400 3275);
DISPLAY INVISIBLE (-1400 3275);
FORCEPROP 2 LAST BOM_COST SB
J 0
(-1650 3325);
DISPLAY 1.361702 (-1650 3325);
PAINT ORANGE (-1650 3325);
DISPLAY INVISIBLE (-1650 3325);
FORCEPROP 2 LAST ROOM SB
J 0
(-1650 3325);
DISPLAY 1.361702 (-1650 3325);
PAINT ORANGE (-1650 3325);
DISPLAY INVISIBLE (-1650 3325);
FORCEPROP 1 LAST OFFPAGE TRUE
J 0
(-1075 3150);
DISPLAY 0.872340 (-1075 3150);
PAINT GREEN (-1075 3150);
DISPLAY INVISIBLE (-1075 3150);
FORCEPROP 1 LAST COMMENT_BODY TRUE
J 0
(-1275 3175);
DISPLAY 0.872340 (-1275 3175);
PAINT GREEN (-1275 3175);
DISPLAY INVISIBLE (-1275 3175);
FORCEPROP 2 LAST PATH I34
J 0
(-1675 3325);
DISPLAY 1.021277 (-1675 3325);
PAINT ORANGE (-1675 3325);
DISPLAY INVISIBLE (-1675 3325);
FORCEADD OFFPAGE..1
(-1400 3225);
FORCEPROP 2 LAST $XR0 118 
J 0
(-1682 3225);
DISPLAY 0.638298 (-1682 3225);
PAINT MONO (-1682 3225);
FORCEPROP 2 LAST CDS_LIB mstr_standard
J 0
(-1400 3225);
PAINT ORANGE (-1400 3225);
DISPLAY INVISIBLE (-1400 3225);
FORCEPROP 2 LAST BOM_COST SB
J 0
(-1650 3275);
DISPLAY 1.361702 (-1650 3275);
PAINT ORANGE (-1650 3275);
DISPLAY INVISIBLE (-1650 3275);
FORCEPROP 2 LAST ROOM SB
J 0
(-1650 3275);
DISPLAY 1.361702 (-1650 3275);
PAINT ORANGE (-1650 3275);
DISPLAY INVISIBLE (-1650 3275);
FORCEPROP 1 LAST OFFPAGE TRUE
J 0
(-1075 3100);
DISPLAY 0.872340 (-1075 3100);
PAINT GREEN (-1075 3100);
DISPLAY INVISIBLE (-1075 3100);
FORCEPROP 1 LAST COMMENT_BODY TRUE
J 0
(-1275 3125);
DISPLAY 0.872340 (-1275 3125);
PAINT GREEN (-1275 3125);
DISPLAY INVISIBLE (-1275 3125);
FORCEPROP 2 LAST PATH I35
J 0
(-1675 3275);
DISPLAY 1.021277 (-1675 3275);
PAINT ORANGE (-1675 3275);
DISPLAY INVISIBLE (-1675 3275);
FORCEADD OFFPAGE..1
(-1400 3075);
FORCEPROP 2 LAST $XR0 120 
J 0
(-1682 3075);
DISPLAY 0.638298 (-1682 3075);
PAINT MONO (-1682 3075);
FORCEPROP 2 LAST CDS_LIB mstr_standard
J 0
(-1400 3075);
PAINT ORANGE (-1400 3075);
DISPLAY INVISIBLE (-1400 3075);
FORCEPROP 2 LAST BOM_COST SB
J 0
(-1650 3125);
DISPLAY 1.361702 (-1650 3125);
PAINT ORANGE (-1650 3125);
DISPLAY INVISIBLE (-1650 3125);
FORCEPROP 2 LAST ROOM SB
J 0
(-1650 3125);
DISPLAY 1.361702 (-1650 3125);
PAINT ORANGE (-1650 3125);
DISPLAY INVISIBLE (-1650 3125);
FORCEPROP 1 LAST OFFPAGE TRUE
J 0
(-1075 2950);
DISPLAY 0.872340 (-1075 2950);
PAINT GREEN (-1075 2950);
DISPLAY INVISIBLE (-1075 2950);
FORCEPROP 1 LAST COMMENT_BODY TRUE
J 0
(-1275 2975);
DISPLAY 0.872340 (-1275 2975);
PAINT GREEN (-1275 2975);
DISPLAY INVISIBLE (-1275 2975);
FORCEPROP 2 LAST PATH I36
J 0
(-1675 3125);
DISPLAY 1.021277 (-1675 3125);
PAINT ORANGE (-1675 3125);
DISPLAY INVISIBLE (-1675 3125);
FORCEADD OFFPAGE..1
(-1400 3125);
FORCEPROP 2 LAST $XR0 120 
J 0
(-1682 3125);
DISPLAY 0.638298 (-1682 3125);
PAINT MONO (-1682 3125);
FORCEPROP 2 LAST CDS_LIB mstr_standard
J 0
(-1400 3125);
PAINT ORANGE (-1400 3125);
DISPLAY INVISIBLE (-1400 3125);
FORCEPROP 2 LAST BOM_COST SB
J 0
(-1650 3175);
DISPLAY 1.361702 (-1650 3175);
PAINT ORANGE (-1650 3175);
DISPLAY INVISIBLE (-1650 3175);
FORCEPROP 2 LAST ROOM SB
J 0
(-1650 3175);
DISPLAY 1.361702 (-1650 3175);
PAINT ORANGE (-1650 3175);
DISPLAY INVISIBLE (-1650 3175);
FORCEPROP 1 LAST OFFPAGE TRUE
J 0
(-1075 3000);
DISPLAY 0.872340 (-1075 3000);
PAINT GREEN (-1075 3000);
DISPLAY INVISIBLE (-1075 3000);
FORCEPROP 1 LAST COMMENT_BODY TRUE
J 0
(-1275 3025);
DISPLAY 0.872340 (-1275 3025);
PAINT GREEN (-1275 3025);
DISPLAY INVISIBLE (-1275 3025);
FORCEPROP 2 LAST PATH I37
J 0
(-1675 3175);
DISPLAY 1.021277 (-1675 3175);
PAINT ORANGE (-1675 3175);
DISPLAY INVISIBLE (-1675 3175);
FORCEADD OFFPAGE..5
(-1400 2975);
FORCEPROP 2 LAST $XR0 188 
J 0
(-1655 2975);
DISPLAY 0.638298 (-1655 2975);
PAINT MONO (-1655 2975);
FORCEPROP 2 LAST CDS_LIB mstr_standard
J 0
(-1400 2975);
PAINT ORANGE (-1400 2975);
DISPLAY INVISIBLE (-1400 2975);
FORCEPROP 2 LAST ROOM SB
J 0
(-1650 3025);
DISPLAY 1.361702 (-1650 3025);
PAINT ORANGE (-1650 3025);
DISPLAY INVISIBLE (-1650 3025);
FORCEPROP 2 LAST BOM_COST SB
J 0
(-1650 3025);
DISPLAY 1.361702 (-1650 3025);
PAINT ORANGE (-1650 3025);
DISPLAY INVISIBLE (-1650 3025);
FORCEPROP 1 LAST OFFPAGE TRUE
J 0
(-1075 2850);
DISPLAY 0.872340 (-1075 2850);
PAINT GREEN (-1075 2850);
DISPLAY INVISIBLE (-1075 2850);
FORCEPROP 1 LAST COMMENT_BODY TRUE
J 0
(-1300 2900);
DISPLAY 0.872340 (-1300 2900);
PAINT GREEN (-1300 2900);
DISPLAY INVISIBLE (-1300 2900);
FORCEPROP 2 LAST PATH I38
J 0
(-1675 3025);
DISPLAY 1.021277 (-1675 3025);
PAINT ORANGE (-1675 3025);
DISPLAY INVISIBLE (-1675 3025);
FORCEADD GND..1
(-475 2000);
FORCEPROP 3 LASTPIN (-475 2050) SIG_NAME GND\g
J 0
(-465 2060);
DISPLAY 0.659574 (-465 2060);
PAINT MONO (-465 2060);
DISPLAY INVISIBLE (-465 2060);
FORCEPROP 1 LAST VOLTAGE 0
J 0
(-500 2075);
DISPLAY 1.021277 (-500 2075);
PAINT SKYBLUE (-500 2075);
DISPLAY INVISIBLE (-500 2075);
FORCEPROP 2 LAST CDS_LIB mstr_symbols
J 0
(-475 2000);
PAINT ORANGE (-475 2000);
DISPLAY INVISIBLE (-475 2000);
FORCEPROP 1 LAST SIZE 1B
J 0
(-400 1950);
DISPLAY 0.872340 (-400 1950);
PAINT GREEN (-400 1950);
DISPLAY INVISIBLE (-400 1950);
FORCEPROP 1 LAST BODY_TYPE PLUMBING
J 0
(-520 1957);
DISPLAY 0.340426 (-520 1957);
PAINT GREEN (-520 1957);
DISPLAY INVISIBLE (-520 1957);
FORCEPROP 1 LAST PATH I39
J 0
(-400 2000);
DISPLAY 0.872340 (-400 2000);
PAINT AQUA (-400 2000);
DISPLAY INVISIBLE (-400 2000);
FORCEPROP 1 LAST HDL_POWER GND
J 0
(-475 2150);
DISPLAY 0.872340 (-475 2150);
PAINT GREEN (-475 2150);
DISPLAY INVISIBLE (-475 2150);
FORCEADD CAP_A..1
(475 1300);
FORCEPROP 1 LAST LOCATION C2R16
J 0
(525 1400);
DISPLAY 0.617021 (525 1400);
PAINT AQUA (525 1400);
FORCEPROP 1 LAST PART_NUMBER A36096-030
J 0
(525 1150);
DISPLAY 0.617021 (525 1150);
PAINT BLUE (525 1150);
FORCEPROP 1 LAST VALUE 0.1UF
J 0
(525 1350);
DISPLAY 0.617021 (525 1350);
PAINT SKYBLUE (525 1350);
FORCEPROP 1 LAST TOLERANCE 10%
J 0
(525 1250);
DISPLAY 0.617021 (525 1250);
PAINT SKYBLUE (525 1250);
FORCEPROP 1 LAST PACK_TYPE 0402V
J 0
(525 1100);
DISPLAY 0.617021 (525 1100);
PAINT SKYBLUE (525 1100);
FORCEPROP 1 LAST VOLTAGE 16V
J 0
(525 1300);
DISPLAY 0.617021 (525 1300);
PAINT SKYBLUE (525 1300);
FORCEPROP 1 LAST MATERIAL X7R
J 0
(525 1200);
DISPLAY 0.617021 (525 1200);
PAINT SKYBLUE (525 1200);
FORCEPROP 1 LASTPIN (475 1400) $PN 1
J 0
(485 1380);
DISPLAY 0.617021 (485 1380);
PAINT WHITE (485 1380);
FORCEPROP 1 LASTPIN (475 1200) $PN 2
J 0
(485 1180);
DISPLAY 0.617021 (485 1180);
PAINT WHITE (485 1180);
FORCEPROP 1 LAST PATH I40
J 0
(525 1450);
DISPLAY 0.978723 (525 1450);
PAINT WHITE (525 1450);
DISPLAY INVISIBLE (525 1450);
FORCEPROP 2 LAST ROOM IO_MODULE
J 1
(525 1450);
DISPLAY 0.744681 (525 1450);
PAINT ORANGE (525 1450);
DISPLAY INVISIBLE (525 1450);
FORCEPROP 2 LAST BOM_COST IO_MODULE
J 0
(475 1300);
DISPLAY 0.744681 (475 1300);
PAINT MONO (475 1300);
DISPLAY INVISIBLE (475 1300);
FORCEPROP 2 LAST CDS_LIB dev_discrete
J 0
(475 1300);
PAINT ORANGE (475 1300);
DISPLAY INVISIBLE (475 1300);
FORCEPROP 2 LAST CDS_SEC 1
J 1
(525 1500);
DISPLAY 0.744681 (525 1500);
PAINT MONO (525 1500);
DISPLAY INVISIBLE (525 1500);
FORCEPROP 2 LAST $SEC 1
J 1
(525 1500);
DISPLAY 0.744681 (525 1500);
PAINT MONO (525 1500);
DISPLAY INVISIBLE (525 1500);
FORCEADD CAP..1
(-75 1300);
FORCEPROP 1 LAST LOCATION C2P10
J 0
(-25 1400);
DISPLAY 0.617021 (-25 1400);
PAINT AQUA (-25 1400);
FORCEPROP 1 LAST PART_NUMBER D38464-005
J 0
(-25 1150);
DISPLAY 0.617021 (-25 1150);
PAINT BLUE (-25 1150);
FORCEPROP 1 LAST VALUE 22UF
J 0
(-25 1350);
DISPLAY 0.617021 (-25 1350);
PAINT SKYBLUE (-25 1350);
FORCEPROP 1 LAST TOLERANCE 10%
J 0
(-25 1250);
DISPLAY 0.617021 (-25 1250);
PAINT SKYBLUE (-25 1250);
FORCEPROP 1 LAST PACK_TYPE 1206LF
J 0
(-25 1100);
DISPLAY 0.617021 (-25 1100);
PAINT SKYBLUE (-25 1100);
FORCEPROP 1 LAST VOLTAGE 16V
J 0
(-25 1300);
DISPLAY 0.617021 (-25 1300);
PAINT SKYBLUE (-25 1300);
FORCEPROP 1 LAST MATERIAL X6S
J 0
(-25 1200);
DISPLAY 0.617021 (-25 1200);
PAINT SKYBLUE (-25 1200);
FORCEPROP 1 LASTPIN (-75 1200) $PN 2
J 0
(-65 1180);
DISPLAY 0.617021 (-65 1180);
PAINT WHITE (-65 1180);
FORCEPROP 1 LASTPIN (-75 1400) $PN 1
J 0
(-65 1380);
DISPLAY 0.617021 (-65 1380);
PAINT WHITE (-65 1380);
FORCEPROP 2 LAST SEC_TYPE 1206LF
J 0
(-25 1500);
DISPLAY 1.021277 (-25 1500);
PAINT ORANGE (-25 1500);
DISPLAY INVISIBLE (-25 1500);
FORCEPROP 2 LAST BOM_COST IO_MODULE
J 0
(-75 1300);
DISPLAY 0.744681 (-75 1300);
PAINT MONO (-75 1300);
DISPLAY INVISIBLE (-75 1300);
FORCEPROP 2 LAST CDS_LIB mstr_discrete
J 1
(-75 1300);
DISPLAY 0.744681 (-75 1300);
PAINT ORANGE (-75 1300);
DISPLAY INVISIBLE (-75 1300);
FORCEPROP 2 LAST SEC 1
J 0
(-25 1500);
DISPLAY 0.680851 (-25 1500);
PAINT MONO (-25 1500);
DISPLAY INVISIBLE (-25 1500);
FORCEPROP 1 LAST PATH I41
J 0
(-25 1450);
DISPLAY 0.978723 (-25 1450);
PAINT WHITE (-25 1450);
DISPLAY INVISIBLE (-25 1450);
FORCEPROP 2 LAST ROOM IO_MODULE
J 1
(-25 1450);
DISPLAY 0.744681 (-25 1450);
PAINT ORANGE (-25 1450);
DISPLAY INVISIBLE (-25 1450);
FORCEADD OFFPAGE..5
(-1400 2925);
FORCEPROP 2 LAST $XR0 188 
J 0
(-1655 2925);
DISPLAY 0.638298 (-1655 2925);
PAINT MONO (-1655 2925);
FORCEPROP 2 LAST BOM_COST SB
J 0
(-1650 2975);
DISPLAY 1.361702 (-1650 2975);
PAINT ORANGE (-1650 2975);
DISPLAY INVISIBLE (-1650 2975);
FORCEPROP 2 LAST ROOM SB
J 0
(-1650 2975);
DISPLAY 1.361702 (-1650 2975);
PAINT ORANGE (-1650 2975);
DISPLAY INVISIBLE (-1650 2975);
FORCEPROP 2 LAST CDS_LIB mstr_standard
J 0
(-1400 2925);
PAINT ORANGE (-1400 2925);
DISPLAY INVISIBLE (-1400 2925);
FORCEPROP 1 LAST OFFPAGE TRUE
J 0
(-1075 2800);
DISPLAY 0.872340 (-1075 2800);
PAINT GREEN (-1075 2800);
DISPLAY INVISIBLE (-1075 2800);
FORCEPROP 1 LAST COMMENT_BODY TRUE
J 0
(-1300 2850);
DISPLAY 0.872340 (-1300 2850);
PAINT GREEN (-1300 2850);
DISPLAY INVISIBLE (-1300 2850);
FORCEPROP 2 LAST PATH I42
J 0
(-1675 2975);
DISPLAY 1.021277 (-1675 2975);
PAINT ORANGE (-1675 2975);
DISPLAY INVISIBLE (-1675 2975);
FORCEADD OFFPAGE..5
(-1400 2675);
FORCEPROP 2 LAST $XR0 188 
J 0
(-1655 2675);
DISPLAY 0.638298 (-1655 2675);
PAINT MONO (-1655 2675);
FORCEPROP 2 LAST ROOM SB
J 0
(-1650 2725);
DISPLAY 1.361702 (-1650 2725);
PAINT ORANGE (-1650 2725);
DISPLAY INVISIBLE (-1650 2725);
FORCEPROP 2 LAST BOM_COST SB
J 0
(-1650 2725);
DISPLAY 1.361702 (-1650 2725);
PAINT ORANGE (-1650 2725);
DISPLAY INVISIBLE (-1650 2725);
FORCEPROP 2 LAST CDS_LIB mstr_standard
J 0
(-1400 2675);
PAINT ORANGE (-1400 2675);
DISPLAY INVISIBLE (-1400 2675);
FORCEPROP 1 LAST OFFPAGE TRUE
J 0
(-1075 2550);
DISPLAY 0.872340 (-1075 2550);
PAINT GREEN (-1075 2550);
DISPLAY INVISIBLE (-1075 2550);
FORCEPROP 1 LAST COMMENT_BODY TRUE
J 0
(-1300 2600);
DISPLAY 0.872340 (-1300 2600);
PAINT GREEN (-1300 2600);
DISPLAY INVISIBLE (-1300 2600);
FORCEPROP 2 LAST PATH I45
J 0
(-1675 2725);
DISPLAY 1.021277 (-1675 2725);
PAINT ORANGE (-1675 2725);
DISPLAY INVISIBLE (-1675 2725);
FORCEADD OFFPAGE..5
(-1400 2625);
FORCEPROP 2 LAST $XR0 188 
J 0
(-1655 2625);
DISPLAY 0.638298 (-1655 2625);
PAINT MONO (-1655 2625);
FORCEPROP 2 LAST BOM_COST SB
J 0
(-1650 2675);
DISPLAY 1.361702 (-1650 2675);
PAINT ORANGE (-1650 2675);
DISPLAY INVISIBLE (-1650 2675);
FORCEPROP 2 LAST ROOM SB
J 0
(-1650 2675);
DISPLAY 1.361702 (-1650 2675);
PAINT ORANGE (-1650 2675);
DISPLAY INVISIBLE (-1650 2675);
FORCEPROP 2 LAST CDS_LIB mstr_standard
J 0
(-1400 2625);
PAINT ORANGE (-1400 2625);
DISPLAY INVISIBLE (-1400 2625);
FORCEPROP 1 LAST OFFPAGE TRUE
J 0
(-1075 2500);
DISPLAY 0.872340 (-1075 2500);
PAINT GREEN (-1075 2500);
DISPLAY INVISIBLE (-1075 2500);
FORCEPROP 1 LAST COMMENT_BODY TRUE
J 0
(-1300 2550);
DISPLAY 0.872340 (-1300 2550);
PAINT GREEN (-1300 2550);
DISPLAY INVISIBLE (-1300 2550);
FORCEPROP 2 LAST PATH I46
J 0
(-1675 2675);
DISPLAY 1.021277 (-1675 2675);
PAINT ORANGE (-1675 2675);
DISPLAY INVISIBLE (-1675 2675);
FORCEADD CAP_A..1
(-525 1300);
FORCEPROP 1 LAST LOCATION C2P16
J 0
(-475 1400);
DISPLAY 0.617021 (-475 1400);
PAINT AQUA (-475 1400);
FORCEPROP 1 LAST PART_NUMBER A36096-030
J 0
(-475 1150);
DISPLAY 0.617021 (-475 1150);
PAINT BLUE (-475 1150);
FORCEPROP 1 LAST VALUE 0.1UF
J 0
(-475 1350);
DISPLAY 0.617021 (-475 1350);
PAINT SKYBLUE (-475 1350);
FORCEPROP 1 LAST TOLERANCE 10%
J 0
(-475 1250);
DISPLAY 0.617021 (-475 1250);
PAINT SKYBLUE (-475 1250);
FORCEPROP 1 LAST PACK_TYPE 0402V
J 0
(-475 1100);
DISPLAY 0.617021 (-475 1100);
PAINT SKYBLUE (-475 1100);
FORCEPROP 1 LAST VOLTAGE 16V
J 0
(-475 1300);
DISPLAY 0.617021 (-475 1300);
PAINT SKYBLUE (-475 1300);
FORCEPROP 1 LAST MATERIAL X7R
J 0
(-475 1200);
DISPLAY 0.617021 (-475 1200);
PAINT SKYBLUE (-475 1200);
FORCEPROP 1 LASTPIN (-525 1400) $PN 1
J 0
(-515 1380);
DISPLAY 0.617021 (-515 1380);
PAINT WHITE (-515 1380);
FORCEPROP 1 LASTPIN (-525 1200) $PN 2
J 0
(-515 1180);
DISPLAY 0.617021 (-515 1180);
PAINT WHITE (-515 1180);
FORCEPROP 1 LAST PATH I53
J 0
(-475 1450);
DISPLAY 0.978723 (-475 1450);
PAINT WHITE (-475 1450);
DISPLAY INVISIBLE (-475 1450);
FORCEPROP 2 LAST ROOM IO_MODULE
J 1
(-475 1450);
DISPLAY 0.744681 (-475 1450);
PAINT ORANGE (-475 1450);
DISPLAY INVISIBLE (-475 1450);
FORCEPROP 2 LAST BOM_COST IO_MODULE
J 0
(-525 1300);
DISPLAY 0.744681 (-525 1300);
PAINT MONO (-525 1300);
DISPLAY INVISIBLE (-525 1300);
FORCEPROP 2 LAST CDS_LIB dev_discrete
J 0
(-525 1300);
PAINT ORANGE (-525 1300);
DISPLAY INVISIBLE (-525 1300);
FORCEPROP 2 LAST CDS_SEC 1
J 1
(-475 1500);
DISPLAY 0.744681 (-475 1500);
PAINT MONO (-475 1500);
DISPLAY INVISIBLE (-475 1500);
FORCEPROP 2 LAST $SEC 1
J 1
(-475 1500);
DISPLAY 0.744681 (-475 1500);
PAINT MONO (-475 1500);
DISPLAY INVISIBLE (-475 1500);
FORCEADD CAP_A..1
(-950 1300);
FORCEPROP 1 LAST LOCATION C2P15
J 0
(-900 1400);
DISPLAY 0.617021 (-900 1400);
PAINT AQUA (-900 1400);
FORCEPROP 1 LAST PART_NUMBER A36096-030
J 0
(-900 1150);
DISPLAY 0.617021 (-900 1150);
PAINT BLUE (-900 1150);
FORCEPROP 1 LAST VALUE 0.1UF
J 0
(-900 1350);
DISPLAY 0.617021 (-900 1350);
PAINT SKYBLUE (-900 1350);
FORCEPROP 1 LAST TOLERANCE 10%
J 0
(-900 1250);
DISPLAY 0.617021 (-900 1250);
PAINT SKYBLUE (-900 1250);
FORCEPROP 1 LAST PACK_TYPE 0402V
J 0
(-900 1100);
DISPLAY 0.617021 (-900 1100);
PAINT SKYBLUE (-900 1100);
FORCEPROP 1 LAST VOLTAGE 16V
J 0
(-900 1300);
DISPLAY 0.617021 (-900 1300);
PAINT SKYBLUE (-900 1300);
FORCEPROP 1 LAST MATERIAL X7R
J 0
(-900 1200);
DISPLAY 0.617021 (-900 1200);
PAINT SKYBLUE (-900 1200);
FORCEPROP 1 LASTPIN (-950 1400) $PN 1
J 0
(-940 1380);
DISPLAY 0.617021 (-940 1380);
PAINT WHITE (-940 1380);
FORCEPROP 1 LASTPIN (-950 1200) $PN 2
J 0
(-940 1180);
DISPLAY 0.617021 (-940 1180);
PAINT WHITE (-940 1180);
FORCEPROP 1 LAST PATH I55
J 0
(-900 1450);
DISPLAY 0.978723 (-900 1450);
PAINT WHITE (-900 1450);
DISPLAY INVISIBLE (-900 1450);
FORCEPROP 2 LAST ROOM IO_MODULE
J 1
(-900 1450);
DISPLAY 0.744681 (-900 1450);
PAINT ORANGE (-900 1450);
DISPLAY INVISIBLE (-900 1450);
FORCEPROP 2 LAST BOM_COST IO_MODULE
J 0
(-950 1300);
DISPLAY 0.744681 (-950 1300);
PAINT MONO (-950 1300);
DISPLAY INVISIBLE (-950 1300);
FORCEPROP 2 LAST CDS_LIB dev_discrete
J 0
(-950 1300);
PAINT ORANGE (-950 1300);
DISPLAY INVISIBLE (-950 1300);
FORCEPROP 2 LAST CDS_SEC 1
J 1
(-900 1500);
DISPLAY 0.744681 (-900 1500);
PAINT MONO (-900 1500);
DISPLAY INVISIBLE (-900 1500);
FORCEPROP 2 LAST $SEC 1
J 1
(-900 1500);
DISPLAY 0.744681 (-900 1500);
PAINT MONO (-900 1500);
DISPLAY INVISIBLE (-900 1500);
FORCEADD CAP_A..1
(-1400 1300);
FORCEPROP 1 LAST LOCATION C2P14
J 0
(-1350 1400);
DISPLAY 0.617021 (-1350 1400);
PAINT AQUA (-1350 1400);
FORCEPROP 1 LAST PART_NUMBER A36096-030
J 0
(-1350 1150);
DISPLAY 0.617021 (-1350 1150);
PAINT BLUE (-1350 1150);
FORCEPROP 1 LAST VALUE 0.1UF
J 0
(-1350 1350);
DISPLAY 0.617021 (-1350 1350);
PAINT SKYBLUE (-1350 1350);
FORCEPROP 1 LAST TOLERANCE 10%
J 0
(-1350 1250);
DISPLAY 0.617021 (-1350 1250);
PAINT SKYBLUE (-1350 1250);
FORCEPROP 1 LAST PACK_TYPE 0402V
J 0
(-1350 1100);
DISPLAY 0.617021 (-1350 1100);
PAINT SKYBLUE (-1350 1100);
FORCEPROP 1 LAST VOLTAGE 16V
J 0
(-1350 1300);
DISPLAY 0.617021 (-1350 1300);
PAINT SKYBLUE (-1350 1300);
FORCEPROP 1 LAST MATERIAL X7R
J 0
(-1350 1200);
DISPLAY 0.617021 (-1350 1200);
PAINT SKYBLUE (-1350 1200);
FORCEPROP 1 LASTPIN (-1400 1400) $PN 1
J 0
(-1390 1380);
DISPLAY 0.617021 (-1390 1380);
PAINT WHITE (-1390 1380);
FORCEPROP 1 LASTPIN (-1400 1200) $PN 2
J 0
(-1390 1180);
DISPLAY 0.617021 (-1390 1180);
PAINT WHITE (-1390 1180);
FORCEPROP 1 LAST PATH I56
J 0
(-1350 1450);
DISPLAY 0.978723 (-1350 1450);
PAINT WHITE (-1350 1450);
DISPLAY INVISIBLE (-1350 1450);
FORCEPROP 2 LAST ROOM IO_MODULE
J 1
(-1350 1450);
DISPLAY 0.744681 (-1350 1450);
PAINT ORANGE (-1350 1450);
DISPLAY INVISIBLE (-1350 1450);
FORCEPROP 2 LAST BOM_COST IO_MODULE
J 0
(-1400 1300);
DISPLAY 0.744681 (-1400 1300);
PAINT MONO (-1400 1300);
DISPLAY INVISIBLE (-1400 1300);
FORCEPROP 2 LAST CDS_LIB dev_discrete
J 0
(-1400 1300);
PAINT ORANGE (-1400 1300);
DISPLAY INVISIBLE (-1400 1300);
FORCEPROP 2 LAST CDS_SEC 1
J 1
(-1350 1500);
DISPLAY 0.744681 (-1350 1500);
PAINT MONO (-1350 1500);
DISPLAY INVISIBLE (-1350 1500);
FORCEPROP 2 LAST $SEC 1
J 1
(-1350 1500);
DISPLAY 0.744681 (-1350 1500);
PAINT MONO (-1350 1500);
DISPLAY INVISIBLE (-1350 1500);
FORCEADD CAP_A..1
(-1825 1300);
FORCEPROP 1 LAST LOCATION C2P13
J 0
(-1775 1400);
DISPLAY 0.617021 (-1775 1400);
PAINT AQUA (-1775 1400);
FORCEPROP 1 LAST PART_NUMBER A36096-030
J 0
(-1775 1150);
DISPLAY 0.617021 (-1775 1150);
PAINT BLUE (-1775 1150);
FORCEPROP 1 LAST VALUE 0.1UF
J 0
(-1775 1350);
DISPLAY 0.617021 (-1775 1350);
PAINT SKYBLUE (-1775 1350);
FORCEPROP 1 LAST TOLERANCE 10%
J 0
(-1775 1250);
DISPLAY 0.617021 (-1775 1250);
PAINT SKYBLUE (-1775 1250);
FORCEPROP 1 LAST PACK_TYPE 0402V
J 0
(-1775 1100);
DISPLAY 0.617021 (-1775 1100);
PAINT SKYBLUE (-1775 1100);
FORCEPROP 1 LAST VOLTAGE 16V
J 0
(-1775 1300);
DISPLAY 0.617021 (-1775 1300);
PAINT SKYBLUE (-1775 1300);
FORCEPROP 1 LAST MATERIAL X7R
J 0
(-1775 1200);
DISPLAY 0.617021 (-1775 1200);
PAINT SKYBLUE (-1775 1200);
FORCEPROP 1 LASTPIN (-1825 1400) $PN 1
J 0
(-1815 1380);
DISPLAY 0.617021 (-1815 1380);
PAINT WHITE (-1815 1380);
FORCEPROP 1 LASTPIN (-1825 1200) $PN 2
J 0
(-1815 1180);
DISPLAY 0.617021 (-1815 1180);
PAINT WHITE (-1815 1180);
FORCEPROP 1 LAST PATH I57
J 0
(-1775 1450);
DISPLAY 0.978723 (-1775 1450);
PAINT WHITE (-1775 1450);
DISPLAY INVISIBLE (-1775 1450);
FORCEPROP 2 LAST ROOM IO_MODULE
J 1
(-1775 1450);
DISPLAY 0.744681 (-1775 1450);
PAINT ORANGE (-1775 1450);
DISPLAY INVISIBLE (-1775 1450);
FORCEPROP 2 LAST BOM_COST IO_MODULE
J 0
(-1825 1300);
DISPLAY 0.744681 (-1825 1300);
PAINT MONO (-1825 1300);
DISPLAY INVISIBLE (-1825 1300);
FORCEPROP 2 LAST CDS_LIB dev_discrete
J 0
(-1825 1300);
PAINT ORANGE (-1825 1300);
DISPLAY INVISIBLE (-1825 1300);
FORCEPROP 2 LAST CDS_SEC 1
J 1
(-1775 1500);
DISPLAY 0.744681 (-1775 1500);
PAINT MONO (-1775 1500);
DISPLAY INVISIBLE (-1775 1500);
FORCEPROP 2 LAST $SEC 1
J 1
(-1775 1500);
DISPLAY 0.744681 (-1775 1500);
PAINT MONO (-1775 1500);
DISPLAY INVISIBLE (-1775 1500);
FORCEADD GND..1
(200 775);
FORCEPROP 3 LASTPIN (200 825) SIG_NAME GND\g
J 0
(210 835);
DISPLAY 0.659574 (210 835);
PAINT MONO (210 835);
DISPLAY INVISIBLE (210 835);
FORCEPROP 1 LAST VOLTAGE 0
J 0
(175 850);
DISPLAY 1.021277 (175 850);
PAINT SKYBLUE (175 850);
DISPLAY INVISIBLE (175 850);
FORCEPROP 1 LAST SIZE 1B
J 0
(275 725);
DISPLAY 0.872340 (275 725);
PAINT GREEN (275 725);
DISPLAY INVISIBLE (275 725);
FORCEPROP 2 LAST CDS_LIB mstr_symbols
J 1
(200 775);
DISPLAY 0.744681 (200 775);
PAINT ORANGE (200 775);
DISPLAY INVISIBLE (200 775);
FORCEPROP 1 LAST BODY_TYPE PLUMBING
J 0
(155 732);
DISPLAY 0.340426 (155 732);
PAINT GREEN (155 732);
DISPLAY INVISIBLE (155 732);
FORCEPROP 1 LAST PATH I58
J 0
(275 775);
DISPLAY 0.872340 (275 775);
PAINT AQUA (275 775);
DISPLAY INVISIBLE (275 775);
FORCEPROP 1 LAST HDL_POWER GND
J 0
(200 925);
DISPLAY 0.872340 (200 925);
PAINT GREEN (200 925);
DISPLAY INVISIBLE (200 925);
FORCEADD P12V_STBY..1
(875 3925);
FORCEPROP 3 LASTPIN (875 3875) SIG_NAME P12V_STBY\g
J 0
(885 3885);
DISPLAY 0.659574 (885 3885);
PAINT MONO (885 3885);
DISPLAY INVISIBLE (885 3885);
FORCEPROP 1 LAST VOLTAGE 12.0V
J 0
(830 3882);
DISPLAY 0.340426 (830 3882);
PAINT SKYBLUE (830 3882);
DISPLAY INVISIBLE (830 3882);
FORCEPROP 2 LAST CDS_LIB mstr_symbols
J 0
(875 3925);
PAINT ORANGE (875 3925);
DISPLAY INVISIBLE (875 3925);
FORCEPROP 1 LAST SIZE 1B
J 0
(920 3947);
DISPLAY 0.340426 (920 3947);
PAINT GREEN (920 3947);
DISPLAY INVISIBLE (920 3947);
FORCEPROP 1 LAST BODY_TYPE PLUMBING
J 0
(830 3882);
DISPLAY 0.340426 (830 3882);
PAINT GREEN (830 3882);
DISPLAY INVISIBLE (830 3882);
FORCEPROP 1 LAST PATH I59
J 0
(920 3927);
DISPLAY 0.340426 (920 3927);
PAINT GREEN (920 3927);
DISPLAY INVISIBLE (920 3927);
FORCEPROP 1 LAST HDL_POWER P12V_STBY
J 0
(575 3800);
DISPLAY 0.872340 (575 3800);
PAINT ORANGE (575 3800);
DISPLAY INVISIBLE (575 3800);
FORCEADD OFFPAGE..4
(1400 3425);
FORCEPROP 2 LAST $XR0 118 
J 0
(1586 3425);
DISPLAY 0.638298 (1586 3425);
PAINT MONO (1586 3425);
FORCEPROP 2 LAST CDS_LIB mstr_standard
J 0
(1400 3425);
PAINT ORANGE (1400 3425);
DISPLAY INVISIBLE (1400 3425);
FORCEPROP 2 LAST BOM_COST SB
J 0
(1150 3475);
DISPLAY 1.361702 (1150 3475);
PAINT ORANGE (1150 3475);
DISPLAY INVISIBLE (1150 3475);
FORCEPROP 2 LAST ROOM SB
J 0
(1150 3475);
DISPLAY 1.361702 (1150 3475);
PAINT ORANGE (1150 3475);
DISPLAY INVISIBLE (1150 3475);
FORCEPROP 1 LAST OFFPAGE TRUE
J 0
(1725 3300);
DISPLAY 0.872340 (1725 3300);
PAINT GREEN (1725 3300);
DISPLAY INVISIBLE (1725 3300);
FORCEPROP 1 LAST COMMENT_BODY TRUE
J 0
(1375 3325);
DISPLAY 0.872340 (1375 3325);
PAINT GREEN (1375 3325);
DISPLAY INVISIBLE (1375 3325);
FORCEPROP 2 LAST PATH I6
J 0
(1600 3475);
DISPLAY 1.021277 (1600 3475);
PAINT ORANGE (1600 3475);
DISPLAY INVISIBLE (1600 3475);
FORCEADD P12V_STBY..1
(2050 1625);
FORCEPROP 3 LASTPIN (2050 1575) SIG_NAME P12V_STBY\g
J 0
(2060 1585);
DISPLAY 0.659574 (2060 1585);
PAINT MONO (2060 1585);
DISPLAY INVISIBLE (2060 1585);
FORCEPROP 1 LAST VOLTAGE 12.0V
J 0
(2005 1582);
DISPLAY 0.340426 (2005 1582);
PAINT SKYBLUE (2005 1582);
DISPLAY INVISIBLE (2005 1582);
FORCEPROP 1 LAST SIZE 1B
J 0
(2095 1647);
DISPLAY 0.340426 (2095 1647);
PAINT GREEN (2095 1647);
DISPLAY INVISIBLE (2095 1647);
FORCEPROP 2 LAST CDS_LIB mstr_symbols
J 0
(2050 1625);
PAINT ORANGE (2050 1625);
DISPLAY INVISIBLE (2050 1625);
FORCEPROP 1 LAST BODY_TYPE PLUMBING
J 0
(2005 1582);
DISPLAY 0.340426 (2005 1582);
PAINT GREEN (2005 1582);
DISPLAY INVISIBLE (2005 1582);
FORCEPROP 1 LAST PATH I60
J 0
(2095 1627);
DISPLAY 0.340426 (2095 1627);
PAINT GREEN (2095 1627);
DISPLAY INVISIBLE (2095 1627);
FORCEPROP 1 LAST HDL_POWER P12V_STBY
J 0
(1750 1500);
DISPLAY 0.872340 (1750 1500);
PAINT ORANGE (1750 1500);
DISPLAY INVISIBLE (1750 1500);
FORCEADD P12V_STBY..1
(850 1625);
FORCEPROP 3 LASTPIN (850 1575) SIG_NAME P12V_STBY\g
J 0
(860 1585);
DISPLAY 0.659574 (860 1585);
PAINT MONO (860 1585);
DISPLAY INVISIBLE (860 1585);
FORCEPROP 1 LAST VOLTAGE 12.0V
J 0
(805 1582);
DISPLAY 0.340426 (805 1582);
PAINT SKYBLUE (805 1582);
DISPLAY INVISIBLE (805 1582);
FORCEPROP 2 LAST CDS_LIB mstr_symbols
J 0
(850 1625);
PAINT ORANGE (850 1625);
DISPLAY INVISIBLE (850 1625);
FORCEPROP 1 LAST SIZE 1B
J 0
(895 1647);
DISPLAY 0.340426 (895 1647);
PAINT GREEN (895 1647);
DISPLAY INVISIBLE (895 1647);
FORCEPROP 1 LAST BODY_TYPE PLUMBING
J 0
(805 1582);
DISPLAY 0.340426 (805 1582);
PAINT GREEN (805 1582);
DISPLAY INVISIBLE (805 1582);
FORCEPROP 1 LAST PATH I61
J 0
(895 1627);
DISPLAY 0.340426 (895 1627);
PAINT GREEN (895 1627);
DISPLAY INVISIBLE (895 1627);
FORCEPROP 1 LAST HDL_POWER P12V_STBY
J 0
(550 1500);
DISPLAY 0.872340 (550 1500);
PAINT ORANGE (550 1500);
DISPLAY INVISIBLE (550 1500);
FORCEADD P12V_STBY..1
(-1100 1625);
FORCEPROP 3 LASTPIN (-1100 1575) SIG_NAME P12V_STBY\g
J 0
(-1090 1585);
DISPLAY 0.659574 (-1090 1585);
PAINT MONO (-1090 1585);
DISPLAY INVISIBLE (-1090 1585);
FORCEPROP 1 LAST VOLTAGE 12.0V
J 0
(-1145 1582);
DISPLAY 0.340426 (-1145 1582);
PAINT SKYBLUE (-1145 1582);
DISPLAY INVISIBLE (-1145 1582);
FORCEPROP 2 LAST CDS_LIB mstr_symbols
J 0
(-1100 1625);
PAINT ORANGE (-1100 1625);
DISPLAY INVISIBLE (-1100 1625);
FORCEPROP 1 LAST SIZE 1B
J 0
(-1055 1647);
DISPLAY 0.340426 (-1055 1647);
PAINT GREEN (-1055 1647);
DISPLAY INVISIBLE (-1055 1647);
FORCEPROP 1 LAST BODY_TYPE PLUMBING
J 0
(-1145 1582);
DISPLAY 0.340426 (-1145 1582);
PAINT GREEN (-1145 1582);
DISPLAY INVISIBLE (-1145 1582);
FORCEPROP 1 LAST PATH I62
J 0
(-1055 1627);
DISPLAY 0.340426 (-1055 1627);
PAINT GREEN (-1055 1627);
DISPLAY INVISIBLE (-1055 1627);
FORCEPROP 1 LAST HDL_POWER P12V_STBY
J 0
(-1400 1500);
DISPLAY 0.872340 (-1400 1500);
PAINT ORANGE (-1400 1500);
DISPLAY INVISIBLE (-1400 1500);
FORCEADD P12V_STBY..1
(3300 1650);
FORCEPROP 3 LASTPIN (3300 1600) SIG_NAME P12V_STBY\g
J 0
(3310 1610);
DISPLAY 0.659574 (3310 1610);
PAINT MONO (3310 1610);
DISPLAY INVISIBLE (3310 1610);
FORCEPROP 1 LAST VOLTAGE 12.0V
J 0
(3255 1607);
DISPLAY 0.340426 (3255 1607);
PAINT SKYBLUE (3255 1607);
DISPLAY INVISIBLE (3255 1607);
FORCEPROP 2 LAST CDS_LIB mstr_symbols
J 0
(3300 1650);
PAINT ORANGE (3300 1650);
DISPLAY INVISIBLE (3300 1650);
FORCEPROP 1 LAST SIZE 1B
J 0
(3345 1672);
DISPLAY 0.340426 (3345 1672);
PAINT GREEN (3345 1672);
DISPLAY INVISIBLE (3345 1672);
FORCEPROP 1 LAST BODY_TYPE PLUMBING
J 0
(3255 1607);
DISPLAY 0.340426 (3255 1607);
PAINT GREEN (3255 1607);
DISPLAY INVISIBLE (3255 1607);
FORCEPROP 1 LAST PATH I63
J 0
(3345 1652);
DISPLAY 0.340426 (3345 1652);
PAINT GREEN (3345 1652);
DISPLAY INVISIBLE (3345 1652);
FORCEPROP 1 LAST HDL_POWER P12V_STBY
J 0
(3000 1525);
DISPLAY 0.872340 (3000 1525);
PAINT ORANGE (3000 1525);
DISPLAY INVISIBLE (3000 1525);
FORCEADD CAP_A..2
(3075 4925);
FORCEPROP 1 LAST LOCATION C8C8
J 1
(3075 5025);
DISPLAY 0.617021 (3075 5025);
PAINT AQUA (3075 5025);
FORCEPROP 1 LAST PART_NUMBER A36096-030
J 1
(3075 4975);
DISPLAY 0.617021 (3075 4975);
PAINT BLUE (3075 4975);
FORCEPROP 1 LAST VALUE 0.1UF
J 2
(3075 4825);
DISPLAY 0.617021 (3075 4825);
PAINT SKYBLUE (3075 4825);
FORCEPROP 1 LAST TOLERANCE 10%
J 2
(3075 4775);
DISPLAY 0.617021 (3075 4775);
PAINT SKYBLUE (3075 4775);
FORCEPROP 1 LAST PACK_TYPE 0402V
J 1
(3075 4725);
DISPLAY 0.617021 (3075 4725);
PAINT SKYBLUE (3075 4725);
FORCEPROP 1 LAST VOLTAGE 16V
J 0
(3075 4825);
DISPLAY 0.617021 (3075 4825);
PAINT SKYBLUE (3075 4825);
FORCEPROP 1 LAST MATERIAL X7R
J 0
(3075 4775);
DISPLAY 0.617021 (3075 4775);
PAINT SKYBLUE (3075 4775);
FORCEPROP 1 LASTPIN (2975 4925) $PN 1
J 0
(2965 4940);
DISPLAY 0.617021 (2965 4940);
PAINT ORANGE (2965 4940);
FORCEPROP 1 LASTPIN (3175 4925) $PN 2
J 0
(3160 4940);
DISPLAY 0.617021 (3160 4940);
PAINT ORANGE (3160 4940);
FORCEPROP 1 LAST PATH I64
J 0
(3075 5125);
DISPLAY 0.978723 (3075 5125);
PAINT WHITE (3075 5125);
DISPLAY INVISIBLE (3075 5125);
FORCEPROP 2 LAST CDS_LIB dev_discrete
J 0
(3075 4925);
PAINT ORANGE (3075 4925);
DISPLAY INVISIBLE (3075 4925);
FORCEPROP 2 LAST CDS_SEC 1
J 0
(3075 5075);
PAINT ORANGE (3075 5075);
DISPLAY INVISIBLE (3075 5075);
FORCEPROP 2 LAST SEC_TYPE 0402V
J 0
(3075 5175);
DISPLAY 1.021277 (3075 5175);
PAINT ORANGE (3075 5175);
DISPLAY INVISIBLE (3075 5175);
FORCEPROP 2 LAST SEC 1
J 0
(3075 5175);
DISPLAY 0.680851 (3075 5175);
PAINT MONO (3075 5175);
DISPLAY INVISIBLE (3075 5175);
FORCEADD OFFPAGE..1
(2375 4925);
FORCEPROP 2 LAST $XR0 188 
J 0
(2093 4925);
DISPLAY 0.638298 (2093 4925);
PAINT MONO (2093 4925);
FORCEPROP 2 LAST CDS_LIB mstr_standard
J 0
(2375 4925);
PAINT ORANGE (2375 4925);
DISPLAY INVISIBLE (2375 4925);
FORCEPROP 1 LAST OFFPAGE TRUE
J 0
(2700 4800);
DISPLAY 0.872340 (2700 4800);
PAINT GREEN (2700 4800);
DISPLAY INVISIBLE (2700 4800);
FORCEPROP 1 LAST COMMENT_BODY TRUE
J 0
(2500 4825);
DISPLAY 0.872340 (2500 4825);
PAINT GREEN (2500 4825);
DISPLAY INVISIBLE (2500 4825);
FORCEPROP 2 LAST PATH I65
J 0
(2425 5000);
DISPLAY 1.021277 (2425 5000);
PAINT ORANGE (2425 5000);
DISPLAY INVISIBLE (2425 5000);
FORCEADD OFFPAGE..2
(3775 4925);
FORCEPROP 2 LAST $XR0 118 
J 0
(3964 4925);
DISPLAY 0.638298 (3964 4925);
PAINT MONO (3964 4925);
FORCEPROP 2 LAST CDS_LIB mstr_standard
J 0
(3775 4925);
PAINT ORANGE (3775 4925);
DISPLAY INVISIBLE (3775 4925);
FORCEPROP 1 LAST OFFPAGE TRUE
J 0
(4100 4800);
DISPLAY 0.872340 (4100 4800);
PAINT GREEN (4100 4800);
DISPLAY INVISIBLE (4100 4800);
FORCEPROP 1 LAST COMMENT_BODY TRUE
J 0
(3730 4830);
DISPLAY 0.872340 (3730 4830);
PAINT GREEN (3730 4830);
DISPLAY INVISIBLE (3730 4830);
FORCEPROP 2 LAST PATH I66
J 0
(3950 5000);
DISPLAY 1.021277 (3950 5000);
PAINT ORANGE (3950 5000);
DISPLAY INVISIBLE (3950 5000);
FORCEADD OFFPAGE..2
(3775 4600);
FORCEPROP 2 LAST $XR0 118 
J 0
(3964 4600);
DISPLAY 0.638298 (3964 4600);
PAINT MONO (3964 4600);
FORCEPROP 2 LAST CDS_LIB mstr_standard
J 0
(3775 4600);
PAINT ORANGE (3775 4600);
DISPLAY INVISIBLE (3775 4600);
FORCEPROP 1 LAST OFFPAGE TRUE
J 0
(4100 4475);
DISPLAY 0.872340 (4100 4475);
PAINT GREEN (4100 4475);
DISPLAY INVISIBLE (4100 4475);
FORCEPROP 1 LAST COMMENT_BODY TRUE
J 0
(3730 4505);
DISPLAY 0.872340 (3730 4505);
PAINT GREEN (3730 4505);
DISPLAY INVISIBLE (3730 4505);
FORCEPROP 2 LAST PATH I67
J 0
(3950 4675);
DISPLAY 1.021277 (3950 4675);
PAINT ORANGE (3950 4675);
DISPLAY INVISIBLE (3950 4675);
FORCEADD CAP_A..2
(3075 4600);
FORCEPROP 1 LAST LOCATION C8C9
J 1
(3075 4700);
DISPLAY 0.617021 (3075 4700);
PAINT AQUA (3075 4700);
FORCEPROP 1 LAST PART_NUMBER A36096-030
J 1
(3075 4650);
DISPLAY 0.617021 (3075 4650);
PAINT BLUE (3075 4650);
FORCEPROP 1 LAST VALUE 0.1UF
J 2
(3075 4500);
DISPLAY 0.617021 (3075 4500);
PAINT SKYBLUE (3075 4500);
FORCEPROP 1 LAST TOLERANCE 10%
J 2
(3075 4450);
DISPLAY 0.617021 (3075 4450);
PAINT SKYBLUE (3075 4450);
FORCEPROP 1 LAST PACK_TYPE 0402V
J 1
(3075 4400);
DISPLAY 0.617021 (3075 4400);
PAINT SKYBLUE (3075 4400);
FORCEPROP 1 LAST VOLTAGE 16V
J 0
(3075 4500);
DISPLAY 0.617021 (3075 4500);
PAINT SKYBLUE (3075 4500);
FORCEPROP 1 LAST MATERIAL X7R
J 0
(3075 4450);
DISPLAY 0.617021 (3075 4450);
PAINT SKYBLUE (3075 4450);
FORCEPROP 1 LASTPIN (2975 4600) $PN 1
J 0
(2965 4615);
DISPLAY 0.617021 (2965 4615);
PAINT ORANGE (2965 4615);
FORCEPROP 1 LASTPIN (3175 4600) $PN 2
J 0
(3160 4615);
DISPLAY 0.617021 (3160 4615);
PAINT ORANGE (3160 4615);
FORCEPROP 1 LAST PATH I68
J 0
(3075 4800);
DISPLAY 0.978723 (3075 4800);
PAINT WHITE (3075 4800);
DISPLAY INVISIBLE (3075 4800);
FORCEPROP 2 LAST CDS_LIB dev_discrete
J 0
(3075 4600);
PAINT ORANGE (3075 4600);
DISPLAY INVISIBLE (3075 4600);
FORCEPROP 2 LAST CDS_SEC 1
J 0
(3075 4750);
PAINT ORANGE (3075 4750);
DISPLAY INVISIBLE (3075 4750);
FORCEPROP 2 LAST SEC_TYPE 0402V
J 0
(3075 4850);
DISPLAY 1.021277 (3075 4850);
PAINT ORANGE (3075 4850);
DISPLAY INVISIBLE (3075 4850);
FORCEPROP 2 LAST SEC 1
J 0
(3075 4850);
DISPLAY 0.680851 (3075 4850);
PAINT MONO (3075 4850);
DISPLAY INVISIBLE (3075 4850);
FORCEADD OFFPAGE..1
(2375 4600);
FORCEPROP 2 LAST $XR0 188 
J 0
(2093 4600);
DISPLAY 0.638298 (2093 4600);
PAINT MONO (2093 4600);
FORCEPROP 2 LAST CDS_LIB mstr_standard
J 0
(2375 4600);
PAINT ORANGE (2375 4600);
DISPLAY INVISIBLE (2375 4600);
FORCEPROP 1 LAST OFFPAGE TRUE
J 0
(2700 4475);
DISPLAY 0.872340 (2700 4475);
PAINT GREEN (2700 4475);
DISPLAY INVISIBLE (2700 4475);
FORCEPROP 1 LAST COMMENT_BODY TRUE
J 0
(2500 4500);
DISPLAY 0.872340 (2500 4500);
PAINT GREEN (2500 4500);
DISPLAY INVISIBLE (2500 4500);
FORCEPROP 2 LAST PATH I69
J 0
(2425 4675);
DISPLAY 1.021277 (2425 4675);
PAINT ORANGE (2425 4675);
DISPLAY INVISIBLE (2425 4675);
FORCEADD OFFPAGE..4
(1400 3375);
FORCEPROP 2 LAST $XR0 118 
J 0
(1586 3375);
DISPLAY 0.638298 (1586 3375);
PAINT MONO (1586 3375);
FORCEPROP 2 LAST CDS_LIB mstr_standard
J 0
(1400 3375);
PAINT ORANGE (1400 3375);
DISPLAY INVISIBLE (1400 3375);
FORCEPROP 2 LAST BOM_COST SB
J 0
(1150 3425);
DISPLAY 1.361702 (1150 3425);
PAINT ORANGE (1150 3425);
DISPLAY INVISIBLE (1150 3425);
FORCEPROP 2 LAST ROOM SB
J 0
(1150 3425);
DISPLAY 1.361702 (1150 3425);
PAINT ORANGE (1150 3425);
DISPLAY INVISIBLE (1150 3425);
FORCEPROP 1 LAST OFFPAGE TRUE
J 0
(1725 3250);
DISPLAY 0.872340 (1725 3250);
PAINT GREEN (1725 3250);
DISPLAY INVISIBLE (1725 3250);
FORCEPROP 1 LAST COMMENT_BODY TRUE
J 0
(1375 3275);
DISPLAY 0.872340 (1375 3275);
PAINT GREEN (1375 3275);
DISPLAY INVISIBLE (1375 3275);
FORCEPROP 2 LAST PATH I7
J 0
(1600 3425);
DISPLAY 1.021277 (1600 3425);
PAINT ORANGE (1600 3425);
DISPLAY INVISIBLE (1600 3425);
FORCEADD OFFPAGE..2
(3775 3925);
FORCEPROP 2 LAST $XR0 118 
J 0
(3964 3925);
DISPLAY 0.638298 (3964 3925);
PAINT MONO (3964 3925);
FORCEPROP 2 LAST CDS_LIB mstr_standard
J 0
(3775 3925);
PAINT ORANGE (3775 3925);
DISPLAY INVISIBLE (3775 3925);
FORCEPROP 1 LAST OFFPAGE TRUE
J 0
(4100 3800);
DISPLAY 0.872340 (4100 3800);
PAINT GREEN (4100 3800);
DISPLAY INVISIBLE (4100 3800);
FORCEPROP 1 LAST COMMENT_BODY TRUE
J 0
(3730 3830);
DISPLAY 0.872340 (3730 3830);
PAINT GREEN (3730 3830);
DISPLAY INVISIBLE (3730 3830);
FORCEPROP 2 LAST PATH I70
J 0
(3950 4000);
DISPLAY 1.021277 (3950 4000);
PAINT ORANGE (3950 4000);
DISPLAY INVISIBLE (3950 4000);
FORCEADD OFFPAGE..2
(3775 4250);
FORCEPROP 2 LAST $XR0 118 
J 0
(3964 4250);
DISPLAY 0.638298 (3964 4250);
PAINT MONO (3964 4250);
FORCEPROP 2 LAST CDS_LIB mstr_standard
J 0
(3775 4250);
PAINT ORANGE (3775 4250);
DISPLAY INVISIBLE (3775 4250);
FORCEPROP 1 LAST OFFPAGE TRUE
J 0
(4100 4125);
DISPLAY 0.872340 (4100 4125);
PAINT GREEN (4100 4125);
DISPLAY INVISIBLE (4100 4125);
FORCEPROP 1 LAST COMMENT_BODY TRUE
J 0
(3730 4155);
DISPLAY 0.872340 (3730 4155);
PAINT GREEN (3730 4155);
DISPLAY INVISIBLE (3730 4155);
FORCEPROP 2 LAST PATH I71
J 0
(3950 4325);
DISPLAY 1.021277 (3950 4325);
PAINT ORANGE (3950 4325);
DISPLAY INVISIBLE (3950 4325);
FORCEADD CAP_A..2
(3075 4250);
FORCEPROP 1 LAST LOCATION C8C11
J 1
(3075 4350);
DISPLAY 0.617021 (3075 4350);
PAINT AQUA (3075 4350);
FORCEPROP 1 LAST PART_NUMBER A36096-030
J 1
(3075 4300);
DISPLAY 0.617021 (3075 4300);
PAINT BLUE (3075 4300);
FORCEPROP 1 LAST VALUE 0.1UF
J 2
(3075 4150);
DISPLAY 0.617021 (3075 4150);
PAINT SKYBLUE (3075 4150);
FORCEPROP 1 LAST TOLERANCE 10%
J 2
(3075 4100);
DISPLAY 0.617021 (3075 4100);
PAINT SKYBLUE (3075 4100);
FORCEPROP 1 LAST PACK_TYPE 0402V
J 1
(3075 4050);
DISPLAY 0.617021 (3075 4050);
PAINT SKYBLUE (3075 4050);
FORCEPROP 1 LAST VOLTAGE 16V
J 0
(3075 4150);
DISPLAY 0.617021 (3075 4150);
PAINT SKYBLUE (3075 4150);
FORCEPROP 1 LAST MATERIAL X7R
J 0
(3075 4100);
DISPLAY 0.617021 (3075 4100);
PAINT SKYBLUE (3075 4100);
FORCEPROP 1 LASTPIN (2975 4250) $PN 1
J 0
(2965 4265);
DISPLAY 0.617021 (2965 4265);
PAINT ORANGE (2965 4265);
FORCEPROP 1 LASTPIN (3175 4250) $PN 2
J 0
(3160 4265);
DISPLAY 0.617021 (3160 4265);
PAINT ORANGE (3160 4265);
FORCEPROP 1 LAST PATH I72
J 0
(3075 4450);
DISPLAY 0.978723 (3075 4450);
PAINT WHITE (3075 4450);
DISPLAY INVISIBLE (3075 4450);
FORCEPROP 2 LAST CDS_LIB dev_discrete
J 0
(3075 4250);
PAINT ORANGE (3075 4250);
DISPLAY INVISIBLE (3075 4250);
FORCEPROP 2 LAST CDS_SEC 1
J 0
(3075 4400);
PAINT ORANGE (3075 4400);
DISPLAY INVISIBLE (3075 4400);
FORCEPROP 2 LAST SEC_TYPE 0402V
J 0
(3075 4500);
DISPLAY 1.021277 (3075 4500);
PAINT ORANGE (3075 4500);
DISPLAY INVISIBLE (3075 4500);
FORCEPROP 2 LAST SEC 1
J 0
(3075 4500);
DISPLAY 0.680851 (3075 4500);
PAINT MONO (3075 4500);
DISPLAY INVISIBLE (3075 4500);
FORCEADD CAP_A..2
(3075 3925);
FORCEPROP 1 LAST LOCATION C8C10
J 1
(3075 4025);
DISPLAY 0.617021 (3075 4025);
PAINT AQUA (3075 4025);
FORCEPROP 1 LAST PART_NUMBER A36096-030
J 1
(3075 3975);
DISPLAY 0.617021 (3075 3975);
PAINT BLUE (3075 3975);
FORCEPROP 1 LAST VALUE 0.1UF
J 2
(3075 3825);
DISPLAY 0.617021 (3075 3825);
PAINT SKYBLUE (3075 3825);
FORCEPROP 1 LAST TOLERANCE 10%
J 2
(3075 3775);
DISPLAY 0.617021 (3075 3775);
PAINT SKYBLUE (3075 3775);
FORCEPROP 1 LAST PACK_TYPE 0402V
J 1
(3075 3725);
DISPLAY 0.617021 (3075 3725);
PAINT SKYBLUE (3075 3725);
FORCEPROP 1 LAST VOLTAGE 16V
J 0
(3075 3825);
DISPLAY 0.617021 (3075 3825);
PAINT SKYBLUE (3075 3825);
FORCEPROP 1 LAST MATERIAL X7R
J 0
(3075 3775);
DISPLAY 0.617021 (3075 3775);
PAINT SKYBLUE (3075 3775);
FORCEPROP 1 LASTPIN (2975 3925) $PN 1
J 0
(2965 3940);
DISPLAY 0.617021 (2965 3940);
PAINT ORANGE (2965 3940);
FORCEPROP 1 LASTPIN (3175 3925) $PN 2
J 0
(3160 3940);
DISPLAY 0.617021 (3160 3940);
PAINT ORANGE (3160 3940);
FORCEPROP 1 LAST PATH I73
J 0
(3075 4125);
DISPLAY 0.978723 (3075 4125);
PAINT WHITE (3075 4125);
DISPLAY INVISIBLE (3075 4125);
FORCEPROP 2 LAST CDS_LIB dev_discrete
J 0
(3075 3925);
PAINT ORANGE (3075 3925);
DISPLAY INVISIBLE (3075 3925);
FORCEPROP 2 LAST CDS_SEC 1
J 0
(3075 4075);
PAINT ORANGE (3075 4075);
DISPLAY INVISIBLE (3075 4075);
FORCEPROP 2 LAST SEC_TYPE 0402V
J 0
(3075 4175);
DISPLAY 1.021277 (3075 4175);
PAINT ORANGE (3075 4175);
DISPLAY INVISIBLE (3075 4175);
FORCEPROP 2 LAST SEC 1
J 0
(3075 4175);
DISPLAY 0.680851 (3075 4175);
PAINT MONO (3075 4175);
DISPLAY INVISIBLE (3075 4175);
FORCEADD OFFPAGE..1
(2375 3925);
FORCEPROP 2 LAST $XR0 188 
J 0
(2093 3925);
DISPLAY 0.638298 (2093 3925);
PAINT MONO (2093 3925);
FORCEPROP 2 LAST CDS_LIB mstr_standard
J 0
(2375 3925);
PAINT ORANGE (2375 3925);
DISPLAY INVISIBLE (2375 3925);
FORCEPROP 1 LAST OFFPAGE TRUE
J 0
(2700 3800);
DISPLAY 0.872340 (2700 3800);
PAINT GREEN (2700 3800);
DISPLAY INVISIBLE (2700 3800);
FORCEPROP 1 LAST COMMENT_BODY TRUE
J 0
(2500 3825);
DISPLAY 0.872340 (2500 3825);
PAINT GREEN (2500 3825);
DISPLAY INVISIBLE (2500 3825);
FORCEPROP 2 LAST PATH I74
J 0
(2425 4000);
DISPLAY 1.021277 (2425 4000);
PAINT ORANGE (2425 4000);
DISPLAY INVISIBLE (2425 4000);
FORCEADD OFFPAGE..1
(2375 4250);
FORCEPROP 2 LAST $XR0 188 
J 0
(2093 4250);
DISPLAY 0.638298 (2093 4250);
PAINT MONO (2093 4250);
FORCEPROP 2 LAST CDS_LIB mstr_standard
J 0
(2375 4250);
PAINT ORANGE (2375 4250);
DISPLAY INVISIBLE (2375 4250);
FORCEPROP 1 LAST OFFPAGE TRUE
J 0
(2700 4125);
DISPLAY 0.872340 (2700 4125);
PAINT GREEN (2700 4125);
DISPLAY INVISIBLE (2700 4125);
FORCEPROP 1 LAST COMMENT_BODY TRUE
J 0
(2500 4150);
DISPLAY 0.872340 (2500 4150);
PAINT GREEN (2500 4150);
DISPLAY INVISIBLE (2500 4150);
FORCEPROP 2 LAST PATH I75
J 0
(2425 4325);
DISPLAY 1.021277 (2425 4325);
PAINT ORANGE (2425 4325);
DISPLAY INVISIBLE (2425 4325);
FORCEADD OFFPAGE..2
(3775 2600);
FORCEPROP 2 LAST $XR0 118 
J 0
(3964 2600);
DISPLAY 0.638298 (3964 2600);
PAINT MONO (3964 2600);
FORCEPROP 2 LAST CDS_LIB mstr_standard
J 0
(3775 2600);
PAINT ORANGE (3775 2600);
DISPLAY INVISIBLE (3775 2600);
FORCEPROP 1 LAST OFFPAGE TRUE
J 0
(4100 2475);
DISPLAY 0.872340 (4100 2475);
PAINT GREEN (4100 2475);
DISPLAY INVISIBLE (4100 2475);
FORCEPROP 1 LAST COMMENT_BODY TRUE
J 0
(3730 2505);
DISPLAY 0.872340 (3730 2505);
PAINT GREEN (3730 2505);
DISPLAY INVISIBLE (3730 2505);
FORCEPROP 2 LAST PATH I76
J 0
(3950 2675);
DISPLAY 1.021277 (3950 2675);
PAINT ORANGE (3950 2675);
DISPLAY INVISIBLE (3950 2675);
FORCEADD OFFPAGE..2
(3775 3600);
FORCEPROP 2 LAST $XR0 118 
J 0
(3964 3600);
DISPLAY 0.638298 (3964 3600);
PAINT MONO (3964 3600);
FORCEPROP 2 LAST CDS_LIB mstr_standard
J 0
(3775 3600);
PAINT ORANGE (3775 3600);
DISPLAY INVISIBLE (3775 3600);
FORCEPROP 1 LAST OFFPAGE TRUE
J 0
(4100 3475);
DISPLAY 0.872340 (4100 3475);
PAINT GREEN (4100 3475);
DISPLAY INVISIBLE (4100 3475);
FORCEPROP 1 LAST COMMENT_BODY TRUE
J 0
(3730 3505);
DISPLAY 0.872340 (3730 3505);
PAINT GREEN (3730 3505);
DISPLAY INVISIBLE (3730 3505);
FORCEPROP 2 LAST PATH I77
J 0
(3950 3675);
DISPLAY 1.021277 (3950 3675);
PAINT ORANGE (3950 3675);
DISPLAY INVISIBLE (3950 3675);
FORCEADD OFFPAGE..2
(3775 3275);
FORCEPROP 2 LAST $XR0 118 
J 0
(3964 3275);
DISPLAY 0.638298 (3964 3275);
PAINT MONO (3964 3275);
FORCEPROP 2 LAST CDS_LIB mstr_standard
J 0
(3775 3275);
PAINT ORANGE (3775 3275);
DISPLAY INVISIBLE (3775 3275);
FORCEPROP 1 LAST OFFPAGE TRUE
J 0
(4100 3150);
DISPLAY 0.872340 (4100 3150);
PAINT GREEN (4100 3150);
DISPLAY INVISIBLE (4100 3150);
FORCEPROP 1 LAST COMMENT_BODY TRUE
J 0
(3730 3180);
DISPLAY 0.872340 (3730 3180);
PAINT GREEN (3730 3180);
DISPLAY INVISIBLE (3730 3180);
FORCEPROP 2 LAST PATH I78
J 0
(3950 3350);
DISPLAY 1.021277 (3950 3350);
PAINT ORANGE (3950 3350);
DISPLAY INVISIBLE (3950 3350);
FORCEADD OFFPAGE..2
(3775 2925);
FORCEPROP 2 LAST $XR0 118 
J 0
(3964 2925);
DISPLAY 0.638298 (3964 2925);
PAINT MONO (3964 2925);
FORCEPROP 2 LAST CDS_LIB mstr_standard
J 0
(3775 2925);
PAINT ORANGE (3775 2925);
DISPLAY INVISIBLE (3775 2925);
FORCEPROP 1 LAST OFFPAGE TRUE
J 0
(4100 2800);
DISPLAY 0.872340 (4100 2800);
PAINT GREEN (4100 2800);
DISPLAY INVISIBLE (4100 2800);
FORCEPROP 1 LAST COMMENT_BODY TRUE
J 0
(3730 2830);
DISPLAY 0.872340 (3730 2830);
PAINT GREEN (3730 2830);
DISPLAY INVISIBLE (3730 2830);
FORCEPROP 2 LAST PATH I79
J 0
(3950 3000);
DISPLAY 1.021277 (3950 3000);
PAINT ORANGE (3950 3000);
DISPLAY INVISIBLE (3950 3000);
FORCEADD OFFPAGE..4
(1400 3275);
FORCEPROP 2 LAST $XR0 120 
J 0
(1586 3275);
DISPLAY 0.638298 (1586 3275);
PAINT MONO (1586 3275);
FORCEPROP 2 LAST BOM_COST SB
J 0
(1150 3325);
DISPLAY 1.361702 (1150 3325);
PAINT ORANGE (1150 3325);
DISPLAY INVISIBLE (1150 3325);
FORCEPROP 2 LAST ROOM SB
J 0
(1150 3325);
DISPLAY 1.361702 (1150 3325);
PAINT ORANGE (1150 3325);
DISPLAY INVISIBLE (1150 3325);
FORCEPROP 2 LAST CDS_LIB mstr_standard
J 0
(1400 3275);
PAINT ORANGE (1400 3275);
DISPLAY INVISIBLE (1400 3275);
FORCEPROP 1 LAST OFFPAGE TRUE
J 0
(1725 3150);
DISPLAY 0.872340 (1725 3150);
PAINT GREEN (1725 3150);
DISPLAY INVISIBLE (1725 3150);
FORCEPROP 1 LAST COMMENT_BODY TRUE
J 0
(1375 3175);
DISPLAY 0.872340 (1375 3175);
PAINT GREEN (1375 3175);
DISPLAY INVISIBLE (1375 3175);
FORCEPROP 2 LAST PATH I8
J 0
(1900 3325);
DISPLAY 1.021277 (1900 3325);
PAINT ORANGE (1900 3325);
DISPLAY INVISIBLE (1900 3325);
FORCEADD CAP_A..2
(3075 3600);
FORCEPROP 1 LAST LOCATION C8C12
J 1
(3075 3700);
DISPLAY 0.617021 (3075 3700);
PAINT AQUA (3075 3700);
FORCEPROP 1 LAST PART_NUMBER A36096-030
J 1
(3075 3650);
DISPLAY 0.617021 (3075 3650);
PAINT BLUE (3075 3650);
FORCEPROP 1 LAST VALUE 0.1UF
J 2
(3075 3500);
DISPLAY 0.617021 (3075 3500);
PAINT SKYBLUE (3075 3500);
FORCEPROP 1 LAST TOLERANCE 10%
J 2
(3075 3450);
DISPLAY 0.617021 (3075 3450);
PAINT SKYBLUE (3075 3450);
FORCEPROP 1 LAST PACK_TYPE 0402V
J 1
(3075 3400);
DISPLAY 0.617021 (3075 3400);
PAINT SKYBLUE (3075 3400);
FORCEPROP 1 LAST VOLTAGE 16V
J 0
(3075 3500);
DISPLAY 0.617021 (3075 3500);
PAINT SKYBLUE (3075 3500);
FORCEPROP 1 LAST MATERIAL X7R
J 0
(3075 3450);
DISPLAY 0.617021 (3075 3450);
PAINT SKYBLUE (3075 3450);
FORCEPROP 1 LASTPIN (2975 3600) $PN 1
J 0
(2965 3615);
DISPLAY 0.617021 (2965 3615);
PAINT ORANGE (2965 3615);
FORCEPROP 1 LASTPIN (3175 3600) $PN 2
J 0
(3160 3615);
DISPLAY 0.617021 (3160 3615);
PAINT ORANGE (3160 3615);
FORCEPROP 1 LAST PATH I80
J 0
(3075 3800);
DISPLAY 0.978723 (3075 3800);
PAINT WHITE (3075 3800);
DISPLAY INVISIBLE (3075 3800);
FORCEPROP 2 LAST CDS_LIB dev_discrete
J 0
(3075 3600);
PAINT ORANGE (3075 3600);
DISPLAY INVISIBLE (3075 3600);
FORCEPROP 2 LAST CDS_SEC 1
J 0
(3075 3750);
PAINT ORANGE (3075 3750);
DISPLAY INVISIBLE (3075 3750);
FORCEPROP 2 LAST SEC_TYPE 0402V
J 0
(3075 3850);
DISPLAY 1.021277 (3075 3850);
PAINT ORANGE (3075 3850);
DISPLAY INVISIBLE (3075 3850);
FORCEPROP 2 LAST SEC 1
J 0
(3075 3750);
DISPLAY 0.680851 (3075 3750);
PAINT MONO (3075 3750);
DISPLAY INVISIBLE (3075 3750);
FORCEADD CAP_A..2
(3075 3275);
FORCEPROP 1 LAST LOCATION C8C13
J 1
(3075 3375);
DISPLAY 0.617021 (3075 3375);
PAINT AQUA (3075 3375);
FORCEPROP 1 LAST PART_NUMBER A36096-030
J 1
(3075 3325);
DISPLAY 0.617021 (3075 3325);
PAINT BLUE (3075 3325);
FORCEPROP 1 LAST VALUE 0.1UF
J 2
(3075 3175);
DISPLAY 0.617021 (3075 3175);
PAINT SKYBLUE (3075 3175);
FORCEPROP 1 LAST TOLERANCE 10%
J 2
(3075 3125);
DISPLAY 0.617021 (3075 3125);
PAINT SKYBLUE (3075 3125);
FORCEPROP 1 LAST PACK_TYPE 0402V
J 1
(3075 3075);
DISPLAY 0.617021 (3075 3075);
PAINT SKYBLUE (3075 3075);
FORCEPROP 1 LAST VOLTAGE 16V
J 0
(3075 3175);
DISPLAY 0.617021 (3075 3175);
PAINT SKYBLUE (3075 3175);
FORCEPROP 1 LAST MATERIAL X7R
J 0
(3075 3125);
DISPLAY 0.617021 (3075 3125);
PAINT SKYBLUE (3075 3125);
FORCEPROP 1 LASTPIN (2975 3275) $PN 1
J 0
(2965 3290);
DISPLAY 0.617021 (2965 3290);
PAINT ORANGE (2965 3290);
FORCEPROP 1 LASTPIN (3175 3275) $PN 2
J 0
(3160 3290);
DISPLAY 0.617021 (3160 3290);
PAINT ORANGE (3160 3290);
FORCEPROP 1 LAST PATH I81
J 0
(3075 3475);
DISPLAY 0.978723 (3075 3475);
PAINT WHITE (3075 3475);
DISPLAY INVISIBLE (3075 3475);
FORCEPROP 2 LAST CDS_LIB dev_discrete
J 0
(3075 3275);
PAINT ORANGE (3075 3275);
DISPLAY INVISIBLE (3075 3275);
FORCEPROP 2 LAST CDS_SEC 1
J 0
(3075 3425);
PAINT ORANGE (3075 3425);
DISPLAY INVISIBLE (3075 3425);
FORCEPROP 2 LAST SEC_TYPE 0402V
J 0
(3075 3525);
DISPLAY 1.021277 (3075 3525);
PAINT ORANGE (3075 3525);
DISPLAY INVISIBLE (3075 3525);
FORCEPROP 2 LAST SEC 1
J 0
(3075 3425);
DISPLAY 0.680851 (3075 3425);
PAINT MONO (3075 3425);
DISPLAY INVISIBLE (3075 3425);
FORCEADD CAP_A..2
(3075 2925);
FORCEPROP 1 LAST LOCATION C8C15
J 1
(3075 3025);
DISPLAY 0.617021 (3075 3025);
PAINT AQUA (3075 3025);
FORCEPROP 1 LAST PART_NUMBER A36096-030
J 1
(3075 2975);
DISPLAY 0.617021 (3075 2975);
PAINT BLUE (3075 2975);
FORCEPROP 1 LAST VALUE 0.1UF
J 2
(3075 2825);
DISPLAY 0.617021 (3075 2825);
PAINT SKYBLUE (3075 2825);
FORCEPROP 1 LAST TOLERANCE 10%
J 2
(3075 2775);
DISPLAY 0.617021 (3075 2775);
PAINT SKYBLUE (3075 2775);
FORCEPROP 1 LAST PACK_TYPE 0402V
J 1
(3075 2725);
DISPLAY 0.617021 (3075 2725);
PAINT SKYBLUE (3075 2725);
FORCEPROP 1 LAST VOLTAGE 16V
J 0
(3075 2825);
DISPLAY 0.617021 (3075 2825);
PAINT SKYBLUE (3075 2825);
FORCEPROP 1 LAST MATERIAL X7R
J 0
(3075 2775);
DISPLAY 0.617021 (3075 2775);
PAINT SKYBLUE (3075 2775);
FORCEPROP 1 LASTPIN (2975 2925) $PN 1
J 0
(2965 2940);
DISPLAY 0.617021 (2965 2940);
PAINT ORANGE (2965 2940);
FORCEPROP 1 LASTPIN (3175 2925) $PN 2
J 0
(3160 2940);
DISPLAY 0.617021 (3160 2940);
PAINT ORANGE (3160 2940);
FORCEPROP 1 LAST PATH I82
J 0
(3075 3125);
DISPLAY 0.978723 (3075 3125);
PAINT WHITE (3075 3125);
DISPLAY INVISIBLE (3075 3125);
FORCEPROP 2 LAST CDS_LIB dev_discrete
J 0
(3075 2925);
PAINT ORANGE (3075 2925);
DISPLAY INVISIBLE (3075 2925);
FORCEPROP 2 LAST CDS_SEC 1
J 0
(3075 3075);
PAINT ORANGE (3075 3075);
DISPLAY INVISIBLE (3075 3075);
FORCEPROP 2 LAST SEC_TYPE 0402V
J 0
(3075 3175);
DISPLAY 1.021277 (3075 3175);
PAINT ORANGE (3075 3175);
DISPLAY INVISIBLE (3075 3175);
FORCEPROP 2 LAST SEC 1
J 0
(3075 3075);
DISPLAY 0.680851 (3075 3075);
PAINT MONO (3075 3075);
DISPLAY INVISIBLE (3075 3075);
FORCEADD OFFPAGE..1
(2375 3600);
FORCEPROP 2 LAST $XR0 188 
J 0
(2093 3600);
DISPLAY 0.638298 (2093 3600);
PAINT MONO (2093 3600);
FORCEPROP 2 LAST CDS_LIB mstr_standard
J 0
(2375 3600);
PAINT ORANGE (2375 3600);
DISPLAY INVISIBLE (2375 3600);
FORCEPROP 1 LAST OFFPAGE TRUE
J 0
(2700 3475);
DISPLAY 0.872340 (2700 3475);
PAINT GREEN (2700 3475);
DISPLAY INVISIBLE (2700 3475);
FORCEPROP 1 LAST COMMENT_BODY TRUE
J 0
(2500 3500);
DISPLAY 0.872340 (2500 3500);
PAINT GREEN (2500 3500);
DISPLAY INVISIBLE (2500 3500);
FORCEPROP 2 LAST PATH I83
J 0
(2425 3675);
DISPLAY 1.021277 (2425 3675);
PAINT ORANGE (2425 3675);
DISPLAY INVISIBLE (2425 3675);
FORCEADD OFFPAGE..1
(2375 3275);
FORCEPROP 2 LAST $XR0 188 
J 0
(2093 3275);
DISPLAY 0.638298 (2093 3275);
PAINT MONO (2093 3275);
FORCEPROP 2 LAST CDS_LIB mstr_standard
J 0
(2375 3275);
PAINT ORANGE (2375 3275);
DISPLAY INVISIBLE (2375 3275);
FORCEPROP 1 LAST OFFPAGE TRUE
J 0
(2700 3150);
DISPLAY 0.872340 (2700 3150);
PAINT GREEN (2700 3150);
DISPLAY INVISIBLE (2700 3150);
FORCEPROP 1 LAST COMMENT_BODY TRUE
J 0
(2500 3175);
DISPLAY 0.872340 (2500 3175);
PAINT GREEN (2500 3175);
DISPLAY INVISIBLE (2500 3175);
FORCEPROP 2 LAST PATH I84
J 0
(2425 3350);
DISPLAY 1.021277 (2425 3350);
PAINT ORANGE (2425 3350);
DISPLAY INVISIBLE (2425 3350);
FORCEADD OFFPAGE..1
(2375 2925);
FORCEPROP 2 LAST $XR0 188 
J 0
(2093 2925);
DISPLAY 0.638298 (2093 2925);
PAINT MONO (2093 2925);
FORCEPROP 2 LAST CDS_LIB mstr_standard
J 0
(2375 2925);
PAINT ORANGE (2375 2925);
DISPLAY INVISIBLE (2375 2925);
FORCEPROP 1 LAST OFFPAGE TRUE
J 0
(2700 2800);
DISPLAY 0.872340 (2700 2800);
PAINT GREEN (2700 2800);
DISPLAY INVISIBLE (2700 2800);
FORCEPROP 1 LAST COMMENT_BODY TRUE
J 0
(2500 2825);
DISPLAY 0.872340 (2500 2825);
PAINT GREEN (2500 2825);
DISPLAY INVISIBLE (2500 2825);
FORCEPROP 2 LAST PATH I85
J 0
(2425 3000);
DISPLAY 1.021277 (2425 3000);
PAINT ORANGE (2425 3000);
DISPLAY INVISIBLE (2425 3000);
FORCEADD CAP_A..2
(3075 2600);
FORCEPROP 1 LAST LOCATION C8C14
J 1
(3075 2700);
DISPLAY 0.617021 (3075 2700);
PAINT AQUA (3075 2700);
FORCEPROP 1 LAST PART_NUMBER A36096-030
J 1
(3075 2650);
DISPLAY 0.617021 (3075 2650);
PAINT BLUE (3075 2650);
FORCEPROP 1 LAST VALUE 0.1UF
J 2
(3075 2500);
DISPLAY 0.617021 (3075 2500);
PAINT SKYBLUE (3075 2500);
FORCEPROP 1 LAST TOLERANCE 10%
J 2
(3075 2450);
DISPLAY 0.617021 (3075 2450);
PAINT SKYBLUE (3075 2450);
FORCEPROP 1 LAST PACK_TYPE 0402V
J 1
(3075 2400);
DISPLAY 0.617021 (3075 2400);
PAINT SKYBLUE (3075 2400);
FORCEPROP 1 LAST VOLTAGE 16V
J 0
(3075 2500);
DISPLAY 0.617021 (3075 2500);
PAINT SKYBLUE (3075 2500);
FORCEPROP 1 LAST MATERIAL X7R
J 0
(3075 2450);
DISPLAY 0.617021 (3075 2450);
PAINT SKYBLUE (3075 2450);
FORCEPROP 1 LASTPIN (2975 2600) $PN 1
J 0
(2965 2615);
DISPLAY 0.617021 (2965 2615);
PAINT ORANGE (2965 2615);
FORCEPROP 1 LASTPIN (3175 2600) $PN 2
J 0
(3160 2615);
DISPLAY 0.617021 (3160 2615);
PAINT ORANGE (3160 2615);
FORCEPROP 1 LAST PATH I86
J 0
(3075 2800);
DISPLAY 0.978723 (3075 2800);
PAINT WHITE (3075 2800);
DISPLAY INVISIBLE (3075 2800);
FORCEPROP 2 LAST CDS_LIB dev_discrete
J 0
(3075 2600);
PAINT ORANGE (3075 2600);
DISPLAY INVISIBLE (3075 2600);
FORCEPROP 2 LAST CDS_SEC 1
J 0
(3075 2750);
PAINT ORANGE (3075 2750);
DISPLAY INVISIBLE (3075 2750);
FORCEPROP 2 LAST SEC_TYPE 0402V
J 0
(3075 2850);
DISPLAY 1.021277 (3075 2850);
PAINT ORANGE (3075 2850);
DISPLAY INVISIBLE (3075 2850);
FORCEPROP 2 LAST SEC 1
J 0
(3075 2750);
DISPLAY 0.680851 (3075 2750);
PAINT MONO (3075 2750);
DISPLAY INVISIBLE (3075 2750);
FORCEADD OFFPAGE..1
(2375 2600);
FORCEPROP 2 LAST $XR0 188 
J 0
(2093 2600);
DISPLAY 0.638298 (2093 2600);
PAINT MONO (2093 2600);
FORCEPROP 2 LAST CDS_LIB mstr_standard
J 0
(2375 2600);
PAINT ORANGE (2375 2600);
DISPLAY INVISIBLE (2375 2600);
FORCEPROP 1 LAST OFFPAGE TRUE
J 0
(2700 2475);
DISPLAY 0.872340 (2700 2475);
PAINT GREEN (2700 2475);
DISPLAY INVISIBLE (2700 2475);
FORCEPROP 1 LAST COMMENT_BODY TRUE
J 0
(2500 2500);
DISPLAY 0.872340 (2500 2500);
PAINT GREEN (2500 2500);
DISPLAY INVISIBLE (2500 2500);
FORCEPROP 2 LAST PATH I87
J 0
(2425 2675);
DISPLAY 1.021277 (2425 2675);
PAINT ORANGE (2425 2675);
DISPLAY INVISIBLE (2425 2675);
FORCEADD RES..1
(-3250 3950);
FORCEPROP 1 LAST LOCATION R1R18
J 0
(-3300 4000);
DISPLAY 0.617021 (-3300 4000);
PAINT AQUA (-3300 4000);
FORCEPROP 1 LAST PART_NUMBER G21796-112
J 0
(-3300 4050);
DISPLAY 0.617021 (-3300 4050);
PAINT BLUE (-3300 4050);
FORCEPROP 1 LAST VALUE 2.21K
J 2
(-3275 3850);
DISPLAY 0.617021 (-3275 3850);
PAINT SKYBLUE (-3275 3850);
FORCEPROP 1 LAST TOLERANCE 1%
J 0
(-3250 3850);
DISPLAY 0.617021 (-3250 3850);
PAINT SKYBLUE (-3250 3850);
FORCEPROP 1 LAST PACK_TYPE 0402
J 0
(-3150 3850);
DISPLAY 0.617021 (-3150 3850);
PAINT SKYBLUE (-3150 3850);
FORCEPROP 1 LAST MATERIAL CHIP
J 0
(-3250 3800);
DISPLAY 0.617021 (-3250 3800);
PAINT SKYBLUE (-3250 3800);
FORCEPROP 1 LAST WATTAGE 1/16W
J 2
(-3275 3800);
DISPLAY 0.617021 (-3275 3800);
PAINT SKYBLUE (-3275 3800);
FORCEPROP 1 LASTPIN (-3150 3950) $PN 2
J 0
(-3188 3962);
DISPLAY 0.617021 (-3188 3962);
PAINT ORANGE (-3188 3962);
FORCEPROP 1 LASTPIN (-3350 3950) $PN 1
J 0
(-3338 3962);
DISPLAY 0.617021 (-3338 3962);
PAINT ORANGE (-3338 3962);
FORCEPROP 2 LAST CDS_LIB mstr_discrete
J 0
(-3250 3950);
PAINT ORANGE (-3250 3950);
DISPLAY INVISIBLE (-3250 3950);
FORCEPROP 2 LAST SEC_TYPE 0402
J 0
(-3300 4150);
DISPLAY 1.021277 (-3300 4150);
PAINT ORANGE (-3300 4150);
DISPLAY INVISIBLE (-3300 4150);
FORCEPROP 2 LAST SEC 1
J 0
(-3300 4150);
DISPLAY 0.680851 (-3300 4150);
PAINT MONO (-3300 4150);
DISPLAY INVISIBLE (-3300 4150);
FORCEPROP 1 LAST PATH I88
J 0
(-3300 4100);
DISPLAY 0.978723 (-3300 4100);
PAINT WHITE (-3300 4100);
DISPLAY INVISIBLE (-3300 4100);
FORCEADD RES..1
(-3250 3650);
FORCEPROP 1 LAST LOCATION R1R19
J 0
(-3300 3700);
DISPLAY 0.617021 (-3300 3700);
PAINT AQUA (-3300 3700);
FORCEPROP 1 LAST PART_NUMBER G21796-112
J 0
(-3300 3750);
DISPLAY 0.617021 (-3300 3750);
PAINT BLUE (-3300 3750);
FORCEPROP 1 LAST VALUE 2.21K
J 2
(-3275 3550);
DISPLAY 0.617021 (-3275 3550);
PAINT SKYBLUE (-3275 3550);
FORCEPROP 1 LAST TOLERANCE 1%
J 0
(-3250 3550);
DISPLAY 0.617021 (-3250 3550);
PAINT SKYBLUE (-3250 3550);
FORCEPROP 1 LAST PACK_TYPE 0402
J 0
(-3150 3550);
DISPLAY 0.617021 (-3150 3550);
PAINT SKYBLUE (-3150 3550);
FORCEPROP 1 LAST MATERIAL CHIP
J 0
(-3250 3500);
DISPLAY 0.617021 (-3250 3500);
PAINT SKYBLUE (-3250 3500);
FORCEPROP 1 LAST WATTAGE 1/16W
J 2
(-3275 3500);
DISPLAY 0.617021 (-3275 3500);
PAINT SKYBLUE (-3275 3500);
FORCEPROP 1 LASTPIN (-3150 3650) $PN 2
J 0
(-3188 3662);
DISPLAY 0.617021 (-3188 3662);
PAINT ORANGE (-3188 3662);
FORCEPROP 1 LASTPIN (-3350 3650) $PN 1
J 0
(-3338 3662);
DISPLAY 0.617021 (-3338 3662);
PAINT ORANGE (-3338 3662);
FORCEPROP 2 LAST CDS_LIB mstr_discrete
J 0
(-3250 3650);
PAINT ORANGE (-3250 3650);
DISPLAY INVISIBLE (-3250 3650);
FORCEPROP 2 LAST SEC_TYPE 0402
J 0
(-3300 3850);
DISPLAY 1.021277 (-3300 3850);
PAINT ORANGE (-3300 3850);
DISPLAY INVISIBLE (-3300 3850);
FORCEPROP 2 LAST SEC 1
J 0
(-3300 3850);
DISPLAY 0.680851 (-3300 3850);
PAINT MONO (-3300 3850);
DISPLAY INVISIBLE (-3300 3850);
FORCEPROP 1 LAST PATH I89
J 0
(-3300 3800);
DISPLAY 0.978723 (-3300 3800);
PAINT WHITE (-3300 3800);
DISPLAY INVISIBLE (-3300 3800);
FORCEADD OFFPAGE..4
(1400 3225);
FORCEPROP 2 LAST $XR0 120 
J 0
(1586 3225);
DISPLAY 0.638298 (1586 3225);
PAINT MONO (1586 3225);
FORCEPROP 2 LAST BOM_COST SB
J 0
(1150 3275);
DISPLAY 1.361702 (1150 3275);
PAINT ORANGE (1150 3275);
DISPLAY INVISIBLE (1150 3275);
FORCEPROP 2 LAST ROOM SB
J 0
(1150 3275);
DISPLAY 1.361702 (1150 3275);
PAINT ORANGE (1150 3275);
DISPLAY INVISIBLE (1150 3275);
FORCEPROP 2 LAST CDS_LIB mstr_standard
J 0
(1400 3225);
PAINT ORANGE (1400 3225);
DISPLAY INVISIBLE (1400 3225);
FORCEPROP 1 LAST OFFPAGE TRUE
J 0
(1725 3100);
DISPLAY 0.872340 (1725 3100);
PAINT GREEN (1725 3100);
DISPLAY INVISIBLE (1725 3100);
FORCEPROP 1 LAST COMMENT_BODY TRUE
J 0
(1375 3125);
DISPLAY 0.872340 (1375 3125);
PAINT GREEN (1375 3125);
DISPLAY INVISIBLE (1375 3125);
FORCEPROP 2 LAST PATH I9
J 0
(1600 3275);
DISPLAY 1.021277 (1600 3275);
PAINT ORANGE (1600 3275);
DISPLAY INVISIBLE (1600 3275);
FORCEADD RES..1
(-3250 3050);
FORCEPROP 1 LAST LOCATION R1R21
J 0
(-3300 3100);
DISPLAY 0.617021 (-3300 3100);
PAINT AQUA (-3300 3100);
FORCEPROP 1 LAST PART_NUMBER G21796-112
J 0
(-3300 3150);
DISPLAY 0.617021 (-3300 3150);
PAINT BLUE (-3300 3150);
FORCEPROP 1 LAST VALUE 2.21K
J 2
(-3275 2950);
DISPLAY 0.617021 (-3275 2950);
PAINT SKYBLUE (-3275 2950);
FORCEPROP 1 LAST TOLERANCE 1%
J 0
(-3250 2950);
DISPLAY 0.617021 (-3250 2950);
PAINT SKYBLUE (-3250 2950);
FORCEPROP 1 LAST PACK_TYPE 0402
J 0
(-3150 2950);
DISPLAY 0.617021 (-3150 2950);
PAINT SKYBLUE (-3150 2950);
FORCEPROP 1 LAST MATERIAL CHIP
J 0
(-3250 2900);
DISPLAY 0.617021 (-3250 2900);
PAINT SKYBLUE (-3250 2900);
FORCEPROP 1 LAST WATTAGE 1/16W
J 2
(-3275 2900);
DISPLAY 0.617021 (-3275 2900);
PAINT SKYBLUE (-3275 2900);
FORCEPROP 1 LASTPIN (-3150 3050) $PN 2
J 0
(-3188 3062);
DISPLAY 0.617021 (-3188 3062);
PAINT ORANGE (-3188 3062);
FORCEPROP 1 LASTPIN (-3350 3050) $PN 1
J 0
(-3338 3062);
DISPLAY 0.617021 (-3338 3062);
PAINT ORANGE (-3338 3062);
FORCEPROP 2 LAST CDS_LIB mstr_discrete
J 0
(-3250 3050);
PAINT ORANGE (-3250 3050);
DISPLAY INVISIBLE (-3250 3050);
FORCEPROP 2 LAST SEC_TYPE 0402
J 0
(-3300 3250);
DISPLAY 1.021277 (-3300 3250);
PAINT ORANGE (-3300 3250);
DISPLAY INVISIBLE (-3300 3250);
FORCEPROP 2 LAST SEC 1
J 0
(-3300 3250);
DISPLAY 0.680851 (-3300 3250);
PAINT MONO (-3300 3250);
DISPLAY INVISIBLE (-3300 3250);
FORCEPROP 1 LAST PATH I90
J 0
(-3300 3200);
DISPLAY 0.978723 (-3300 3200);
PAINT WHITE (-3300 3200);
DISPLAY INVISIBLE (-3300 3200);
FORCEADD RES..1
(-3250 3350);
FORCEPROP 1 LAST LOCATION R1R20
J 0
(-3300 3400);
DISPLAY 0.617021 (-3300 3400);
PAINT AQUA (-3300 3400);
FORCEPROP 1 LAST PART_NUMBER G21796-112
J 0
(-3300 3450);
DISPLAY 0.617021 (-3300 3450);
PAINT BLUE (-3300 3450);
FORCEPROP 1 LAST VALUE 2.21K
J 2
(-3275 3250);
DISPLAY 0.617021 (-3275 3250);
PAINT SKYBLUE (-3275 3250);
FORCEPROP 1 LAST TOLERANCE 1%
J 0
(-3250 3250);
DISPLAY 0.617021 (-3250 3250);
PAINT SKYBLUE (-3250 3250);
FORCEPROP 1 LAST PACK_TYPE 0402
J 0
(-3150 3250);
DISPLAY 0.617021 (-3150 3250);
PAINT SKYBLUE (-3150 3250);
FORCEPROP 1 LAST MATERIAL CHIP
J 0
(-3250 3200);
DISPLAY 0.617021 (-3250 3200);
PAINT SKYBLUE (-3250 3200);
FORCEPROP 1 LAST WATTAGE 1/16W
J 2
(-3275 3200);
DISPLAY 0.617021 (-3275 3200);
PAINT SKYBLUE (-3275 3200);
FORCEPROP 1 LASTPIN (-3150 3350) $PN 2
J 0
(-3188 3362);
DISPLAY 0.617021 (-3188 3362);
PAINT ORANGE (-3188 3362);
FORCEPROP 1 LASTPIN (-3350 3350) $PN 1
J 0
(-3338 3362);
DISPLAY 0.617021 (-3338 3362);
PAINT ORANGE (-3338 3362);
FORCEPROP 2 LAST CDS_LIB mstr_discrete
J 0
(-3250 3350);
PAINT ORANGE (-3250 3350);
DISPLAY INVISIBLE (-3250 3350);
FORCEPROP 2 LAST SEC_TYPE 0402
J 0
(-3300 3550);
DISPLAY 1.021277 (-3300 3550);
PAINT ORANGE (-3300 3550);
DISPLAY INVISIBLE (-3300 3550);
FORCEPROP 2 LAST SEC 1
J 0
(-3300 3550);
DISPLAY 0.680851 (-3300 3550);
PAINT MONO (-3300 3550);
DISPLAY INVISIBLE (-3300 3550);
FORCEPROP 1 LAST PATH I91
J 0
(-3300 3500);
DISPLAY 0.978723 (-3300 3500);
PAINT WHITE (-3300 3500);
DISPLAY INVISIBLE (-3300 3500);
FORCEADD RES..1
(-3250 1825);
FORCEPROP 1 LAST LOCATION R1R22
J 0
(-3300 1875);
DISPLAY 0.617021 (-3300 1875);
PAINT AQUA (-3300 1875);
FORCEPROP 1 LAST PART_NUMBER G21796-112
J 0
(-3300 1925);
DISPLAY 0.617021 (-3300 1925);
PAINT BLUE (-3300 1925);
FORCEPROP 1 LAST VALUE 2.21K
J 2
(-3275 1725);
DISPLAY 0.617021 (-3275 1725);
PAINT SKYBLUE (-3275 1725);
FORCEPROP 1 LAST TOLERANCE 1%
J 0
(-3250 1725);
DISPLAY 0.617021 (-3250 1725);
PAINT SKYBLUE (-3250 1725);
FORCEPROP 1 LAST PACK_TYPE 0402
J 0
(-3150 1725);
DISPLAY 0.617021 (-3150 1725);
PAINT SKYBLUE (-3150 1725);
FORCEPROP 1 LAST MATERIAL CHIP
J 0
(-3250 1675);
DISPLAY 0.617021 (-3250 1675);
PAINT SKYBLUE (-3250 1675);
FORCEPROP 1 LAST WATTAGE 1/16W
J 2
(-3275 1675);
DISPLAY 0.617021 (-3275 1675);
PAINT SKYBLUE (-3275 1675);
FORCEPROP 1 LASTPIN (-3150 1825) $PN 2
J 0
(-3188 1837);
DISPLAY 0.617021 (-3188 1837);
PAINT ORANGE (-3188 1837);
FORCEPROP 1 LASTPIN (-3350 1825) $PN 1
J 0
(-3338 1837);
DISPLAY 0.617021 (-3338 1837);
PAINT ORANGE (-3338 1837);
FORCEPROP 2 LAST CDS_LIB mstr_discrete
J 0
(-3250 1825);
PAINT ORANGE (-3250 1825);
DISPLAY INVISIBLE (-3250 1825);
FORCEPROP 2 LAST SEC_TYPE 0402
J 0
(-3300 2025);
DISPLAY 1.021277 (-3300 2025);
PAINT ORANGE (-3300 2025);
DISPLAY INVISIBLE (-3300 2025);
FORCEPROP 2 LAST SEC 1
J 0
(-3300 2025);
DISPLAY 0.680851 (-3300 2025);
PAINT MONO (-3300 2025);
DISPLAY INVISIBLE (-3300 2025);
FORCEPROP 1 LAST PATH I92
J 0
(-3300 1975);
DISPLAY 0.978723 (-3300 1975);
PAINT WHITE (-3300 1975);
DISPLAY INVISIBLE (-3300 1975);
FORCEADD RES..1
(-3250 2725);
FORCEPROP 1 LAST LOCATION R1R16
J 0
(-3300 2775);
DISPLAY 0.617021 (-3300 2775);
PAINT AQUA (-3300 2775);
FORCEPROP 1 LAST PART_NUMBER G21796-112
J 0
(-3300 2825);
DISPLAY 0.617021 (-3300 2825);
PAINT BLUE (-3300 2825);
FORCEPROP 1 LAST VALUE 2.21K
J 2
(-3275 2625);
DISPLAY 0.617021 (-3275 2625);
PAINT SKYBLUE (-3275 2625);
FORCEPROP 1 LAST TOLERANCE 1%
J 0
(-3250 2625);
DISPLAY 0.617021 (-3250 2625);
PAINT SKYBLUE (-3250 2625);
FORCEPROP 1 LAST PACK_TYPE 0402
J 0
(-3150 2625);
DISPLAY 0.617021 (-3150 2625);
PAINT SKYBLUE (-3150 2625);
FORCEPROP 1 LAST MATERIAL CHIP
J 0
(-3250 2575);
DISPLAY 0.617021 (-3250 2575);
PAINT SKYBLUE (-3250 2575);
FORCEPROP 1 LAST WATTAGE 1/16W
J 2
(-3275 2575);
DISPLAY 0.617021 (-3275 2575);
PAINT SKYBLUE (-3275 2575);
FORCEPROP 1 LASTPIN (-3150 2725) $PN 2
J 0
(-3188 2737);
DISPLAY 0.617021 (-3188 2737);
PAINT ORANGE (-3188 2737);
FORCEPROP 1 LASTPIN (-3350 2725) $PN 1
J 0
(-3338 2737);
DISPLAY 0.617021 (-3338 2737);
PAINT ORANGE (-3338 2737);
FORCEPROP 2 LAST CDS_LIB mstr_discrete
J 0
(-3250 2725);
PAINT ORANGE (-3250 2725);
DISPLAY INVISIBLE (-3250 2725);
FORCEPROP 2 LAST SEC_TYPE 0402
J 0
(-3300 2925);
DISPLAY 1.021277 (-3300 2925);
PAINT ORANGE (-3300 2925);
DISPLAY INVISIBLE (-3300 2925);
FORCEPROP 2 LAST SEC 1
J 0
(-3300 2925);
DISPLAY 0.680851 (-3300 2925);
PAINT MONO (-3300 2925);
DISPLAY INVISIBLE (-3300 2925);
FORCEPROP 1 LAST PATH I93
J 0
(-3300 2875);
DISPLAY 0.978723 (-3300 2875);
PAINT WHITE (-3300 2875);
DISPLAY INVISIBLE (-3300 2875);
FORCEADD RES..1
(-3250 2425);
FORCEPROP 1 LAST LOCATION R1R17
J 0
(-3300 2475);
DISPLAY 0.617021 (-3300 2475);
PAINT AQUA (-3300 2475);
FORCEPROP 1 LAST PART_NUMBER G21796-112
J 0
(-3300 2525);
DISPLAY 0.617021 (-3300 2525);
PAINT BLUE (-3300 2525);
FORCEPROP 1 LAST VALUE 2.21K
J 2
(-3275 2325);
DISPLAY 0.617021 (-3275 2325);
PAINT SKYBLUE (-3275 2325);
FORCEPROP 1 LAST TOLERANCE 1%
J 0
(-3250 2325);
DISPLAY 0.617021 (-3250 2325);
PAINT SKYBLUE (-3250 2325);
FORCEPROP 1 LAST PACK_TYPE 0402
J 0
(-3150 2325);
DISPLAY 0.617021 (-3150 2325);
PAINT SKYBLUE (-3150 2325);
FORCEPROP 1 LAST MATERIAL CHIP
J 0
(-3250 2275);
DISPLAY 0.617021 (-3250 2275);
PAINT SKYBLUE (-3250 2275);
FORCEPROP 1 LAST WATTAGE 1/16W
J 2
(-3275 2275);
DISPLAY 0.617021 (-3275 2275);
PAINT SKYBLUE (-3275 2275);
FORCEPROP 1 LASTPIN (-3150 2425) $PN 2
J 0
(-3188 2437);
DISPLAY 0.617021 (-3188 2437);
PAINT ORANGE (-3188 2437);
FORCEPROP 1 LASTPIN (-3350 2425) $PN 1
J 0
(-3338 2437);
DISPLAY 0.617021 (-3338 2437);
PAINT ORANGE (-3338 2437);
FORCEPROP 2 LAST CDS_LIB mstr_discrete
J 0
(-3250 2425);
PAINT ORANGE (-3250 2425);
DISPLAY INVISIBLE (-3250 2425);
FORCEPROP 2 LAST SEC_TYPE 0402
J 0
(-3300 2625);
DISPLAY 1.021277 (-3300 2625);
PAINT ORANGE (-3300 2625);
DISPLAY INVISIBLE (-3300 2625);
FORCEPROP 2 LAST SEC 1
J 0
(-3300 2625);
DISPLAY 0.680851 (-3300 2625);
PAINT MONO (-3300 2625);
DISPLAY INVISIBLE (-3300 2625);
FORCEPROP 1 LAST PATH I94
J 0
(-3300 2575);
DISPLAY 0.978723 (-3300 2575);
PAINT WHITE (-3300 2575);
DISPLAY INVISIBLE (-3300 2575);
FORCEADD RES..1
(-3250 2125);
FORCEPROP 1 LAST LOCATION R1R23
J 0
(-3300 2175);
DISPLAY 0.617021 (-3300 2175);
PAINT AQUA (-3300 2175);
FORCEPROP 1 LAST PART_NUMBER G21796-112
J 0
(-3300 2225);
DISPLAY 0.617021 (-3300 2225);
PAINT BLUE (-3300 2225);
FORCEPROP 1 LAST VALUE 2.21K
J 2
(-3275 2025);
DISPLAY 0.617021 (-3275 2025);
PAINT SKYBLUE (-3275 2025);
FORCEPROP 1 LAST TOLERANCE 1%
J 0
(-3250 2025);
DISPLAY 0.617021 (-3250 2025);
PAINT SKYBLUE (-3250 2025);
FORCEPROP 1 LAST PACK_TYPE 0402
J 0
(-3150 2025);
DISPLAY 0.617021 (-3150 2025);
PAINT SKYBLUE (-3150 2025);
FORCEPROP 1 LAST MATERIAL CHIP
J 0
(-3250 1975);
DISPLAY 0.617021 (-3250 1975);
PAINT SKYBLUE (-3250 1975);
FORCEPROP 1 LAST WATTAGE 1/16W
J 2
(-3275 1975);
DISPLAY 0.617021 (-3275 1975);
PAINT SKYBLUE (-3275 1975);
FORCEPROP 1 LASTPIN (-3150 2125) $PN 2
J 0
(-3188 2137);
DISPLAY 0.617021 (-3188 2137);
PAINT ORANGE (-3188 2137);
FORCEPROP 1 LASTPIN (-3350 2125) $PN 1
J 0
(-3338 2137);
DISPLAY 0.617021 (-3338 2137);
PAINT ORANGE (-3338 2137);
FORCEPROP 2 LAST CDS_LIB mstr_discrete
J 0
(-3250 2125);
PAINT ORANGE (-3250 2125);
DISPLAY INVISIBLE (-3250 2125);
FORCEPROP 2 LAST SEC_TYPE 0402
J 0
(-3300 2325);
DISPLAY 1.021277 (-3300 2325);
PAINT ORANGE (-3300 2325);
DISPLAY INVISIBLE (-3300 2325);
FORCEPROP 2 LAST SEC 1
J 0
(-3300 2325);
DISPLAY 0.680851 (-3300 2325);
PAINT MONO (-3300 2325);
DISPLAY INVISIBLE (-3300 2325);
FORCEPROP 1 LAST PATH I95
J 0
(-3300 2275);
DISPLAY 0.978723 (-3300 2275);
PAINT WHITE (-3300 2275);
DISPLAY INVISIBLE (-3300 2275);
FORCEADD OFFPAGE..2
(-2450 3950);
FORCEPROP 2 LAST $XR0 120 
J 0
(-2261 3950);
DISPLAY 0.638298 (-2261 3950);
PAINT MONO (-2261 3950);
FORCEPROP 2 LAST $XR1 188 
J 0
(-2141 3950);
DISPLAY 0.638298 (-2141 3950);
PAINT MONO (-2141 3950);
FORCEPROP 2 LAST CDS_LIB mstr_standard
J 0
(-2450 3950);
PAINT ORANGE (-2450 3950);
DISPLAY INVISIBLE (-2450 3950);
FORCEPROP 1 LAST OFFPAGE TRUE
J 0
(-2125 3825);
DISPLAY 0.872340 (-2125 3825);
PAINT GREEN (-2125 3825);
DISPLAY INVISIBLE (-2125 3825);
FORCEPROP 1 LAST COMMENT_BODY TRUE
J 0
(-2495 3855);
DISPLAY 0.872340 (-2495 3855);
PAINT GREEN (-2495 3855);
DISPLAY INVISIBLE (-2495 3855);
FORCEPROP 2 LAST PATH I96
J 0
(-2275 4025);
DISPLAY 1.021277 (-2275 4025);
PAINT ORANGE (-2275 4025);
DISPLAY INVISIBLE (-2275 4025);
FORCEADD OFFPAGE..2
(-2450 3350);
FORCEPROP 2 LAST $XR0 120 
J 0
(-2261 3350);
DISPLAY 0.638298 (-2261 3350);
PAINT MONO (-2261 3350);
FORCEPROP 2 LAST $XR1 188 
J 0
(-2141 3350);
DISPLAY 0.638298 (-2141 3350);
PAINT MONO (-2141 3350);
FORCEPROP 2 LAST CDS_LIB mstr_standard
J 0
(-2450 3350);
PAINT ORANGE (-2450 3350);
DISPLAY INVISIBLE (-2450 3350);
FORCEPROP 1 LAST OFFPAGE TRUE
J 0
(-2125 3225);
DISPLAY 0.872340 (-2125 3225);
PAINT GREEN (-2125 3225);
DISPLAY INVISIBLE (-2125 3225);
FORCEPROP 1 LAST COMMENT_BODY TRUE
J 0
(-2495 3255);
DISPLAY 0.872340 (-2495 3255);
PAINT GREEN (-2495 3255);
DISPLAY INVISIBLE (-2495 3255);
FORCEPROP 2 LAST PATH I97
J 0
(-2275 3425);
DISPLAY 1.021277 (-2275 3425);
PAINT ORANGE (-2275 3425);
DISPLAY INVISIBLE (-2275 3425);
FORCEADD OFFPAGE..2
(-2450 2725);
FORCEPROP 2 LAST $XR0 120 
J 0
(-2261 2725);
DISPLAY 0.638298 (-2261 2725);
PAINT MONO (-2261 2725);
FORCEPROP 2 LAST $XR1 188 
J 0
(-2141 2725);
DISPLAY 0.638298 (-2141 2725);
PAINT MONO (-2141 2725);
FORCEPROP 2 LAST CDS_LIB mstr_standard
J 0
(-2450 2725);
PAINT ORANGE (-2450 2725);
DISPLAY INVISIBLE (-2450 2725);
FORCEPROP 1 LAST OFFPAGE TRUE
J 0
(-2125 2600);
DISPLAY 0.872340 (-2125 2600);
PAINT GREEN (-2125 2600);
DISPLAY INVISIBLE (-2125 2600);
FORCEPROP 1 LAST COMMENT_BODY TRUE
J 0
(-2495 2630);
DISPLAY 0.872340 (-2495 2630);
PAINT GREEN (-2495 2630);
DISPLAY INVISIBLE (-2495 2630);
FORCEPROP 2 LAST PATH I98
J 0
(-2275 2800);
DISPLAY 1.021277 (-2275 2800);
PAINT ORANGE (-2275 2800);
DISPLAY INVISIBLE (-2275 2800);
FORCEADD OFFPAGE..2
(-2450 2125);
FORCEPROP 2 LAST $XR0 120 
J 0
(-2261 2125);
DISPLAY 0.638298 (-2261 2125);
PAINT MONO (-2261 2125);
FORCEPROP 2 LAST $XR1 188 
J 0
(-2141 2125);
DISPLAY 0.638298 (-2141 2125);
PAINT MONO (-2141 2125);
FORCEPROP 2 LAST CDS_LIB mstr_standard
J 0
(-2450 2125);
PAINT ORANGE (-2450 2125);
DISPLAY INVISIBLE (-2450 2125);
FORCEPROP 1 LAST OFFPAGE TRUE
J 0
(-2125 2000);
DISPLAY 0.872340 (-2125 2000);
PAINT GREEN (-2125 2000);
DISPLAY INVISIBLE (-2125 2000);
FORCEPROP 1 LAST COMMENT_BODY TRUE
J 0
(-2495 2030);
DISPLAY 0.872340 (-2495 2030);
PAINT GREEN (-2495 2030);
DISPLAY INVISIBLE (-2495 2030);
FORCEPROP 2 LAST PATH I99
J 0
(-2275 2200);
DISPLAY 1.021277 (-2275 2200);
PAINT ORANGE (-2275 2200);
DISPLAY INVISIBLE (-2275 2200);
FORCEADD CAD_NOTE..1
(2625 2300);
FORCEPROP 0 LAST L1 PLEASE PLACE CAPS WITHIN 1 INCH OF PCH
J 0
(2500 2175);
DISPLAY 1.021277 (2500 2175);
PAINT ORANGE (2500 2175);
FORCEPROP 2 LAST CDS_LIB mstr_symbols
J 0
(2625 2300);
PAINT ORANGE (2625 2300);
DISPLAY INVISIBLE (2625 2300);
FORCEPROP 1 LAST COMMENT_BODY TRUE
J 0
(2650 2400);
DISPLAY 0.978723 (2650 2400);
PAINT ORANGE (2650 2400);
DISPLAY INVISIBLE (2650 2400);
FORCEADD CAD_NOTE..1
(-1700 775);
FORCEPROP 0 LAST L1 PLACE NEAR THE IO SLOT.
J 0
(-1850 675);
DISPLAY 0.617021 (-1850 675);
PAINT WHITE (-1850 675);
FORCEPROP 2 LAST BOM_COST SM_CONTROLLER
J 0
(-1850 725);
DISPLAY 0.744681 (-1850 725);
PAINT MONO (-1850 725);
DISPLAY INVISIBLE (-1850 725);
FORCEPROP 2 LAST CDS_LIB mstr_symbols
J 0
(-1700 775);
DISPLAY 0.744681 (-1700 775);
PAINT MONO (-1700 775);
DISPLAY INVISIBLE (-1700 775);
FORCEPROP 1 LAST COMMENT_BODY TRUE
J 0
(-1675 875);
DISPLAY 0.978723 (-1675 875);
PAINT GREEN (-1675 875);
DISPLAY INVISIBLE (-1675 875);
FORCEPROP 2 LAST ROOM BMC
J 0
(-1850 725);
DISPLAY 0.744681 (-1850 725);
PAINT MONO (-1850 725);
DISPLAY INVISIBLE (-1850 725);
FORCEADD INTEL_CORP_BPAGE..1
(4250 200);
FORCEPROP 1 LAST CDS_CON_LAST_MODIFIED Tue Dec 01 11:52:17 2015
J 0
(2825 525);
PAINT ORANGE (2825 525);
DISPLAY INVISIBLE (2825 525);
FORCEPROP 1 LAST CUSTOM_TXT_CDS <CURRENT_DESIGN_SHEET> OF <TOTAL_DESIGN_SHEETS>
J 0
(3750 225);
PAINT GREEN (3750 225);
FORCEPROP 1 LAST CUSTOM_TXT_CDS <CON_LAST_MODIFIED>
J 0
(2325 550);
PAINT GREEN (2325 550);
FORCEPROP 2 LAST CUSTOM_TXT_CDS <XR_PAGE_TITLE>
J 0
(-3640 5450);
DISPLAY 0.638298 (-3640 5450);
PAINT PINK (-3640 5450);
DISPLAY INVISIBLE (-3640 5450);
FORCEPROP 1 LAST SCH_ADDRESS3 Santa Clara, CA 95052-8119
J 0
(275 225);
DISPLAY 0.617021 (275 225);
PAINT YELLOW (275 225);
FORCEPROP 1 LAST SCH_ADDRESS2 P.O. BOX 58119
J 0
(275 275);
DISPLAY 0.617021 (275 275);
PAINT YELLOW (275 275);
FORCEPROP 1 LAST SCH_ADDRESS1 2200 Mission College Blvd.
J 0
(275 325);
DISPLAY 0.617021 (275 325);
PAINT YELLOW (275 325);
FORCEPROP 1 LAST SCH_TITLE OCP MODULE CONN C
J 0
(-3700 250);
DISPLAY 1.212766 (-3700 250);
PAINT YELLOW (-3700 250);
FORCEPROP 1 LAST SCH_NUMBER H4694802
J 0
(2950 350);
DISPLAY 1.212766 (2950 350);
PAINT YELLOW (2950 350);
FORCEPROP 1 LAST SCH_DEPT BESD
J 1
(-200 300);
DISPLAY 1.212766 (-200 300);
PAINT YELLOW (-200 300);
FORCEPROP 1 LAST SCH_REV 2.420
J 0
(4000 350);
DISPLAY 0.978723 (4000 350);
PAINT YELLOW (4000 350);
FORCEPROP 2 LAST PAGE_BORDER TRUE
J 0
(-3640 5450);
DISPLAY 0.638298 (-3640 5450);
PAINT PINK (-3640 5450);
DISPLAY INVISIBLE (-3640 5450);
FORCEPROP 2 LAST CDS_LIB mstr_symbols
J 0
(4250 200);
PAINT MONO (4250 200);
DISPLAY INVISIBLE (4250 200);
FORCEPROP 1 LAST COMMENT_BODY TRUE
J 0
(4262 212);
DISPLAY 0.468085 (4262 212);
PAINT PEACH (4262 212);
DISPLAY INVISIBLE (4262 212);
FORCEPROP 2 LAST CDS_XR_PAGE_TITLE CR-188 : @BASEBOARD_FAB2_LIB.BASEBOARD_FAB2(SCH_1):PAGE188
J 0
(-3640 5450);
DISPLAY 0.638298 (-3640 5450);
PAINT PINK (-3640 5450);
DISPLAY INVISIBLE (-3640 5450);
WIRE 16 -1 (-3350 1825)(-3475 1825);
WIRE 16 -1 (-3475 2125)(-3475 1825);
WIRE 16 -1 (-3350 2125)(-3475 2125);
WIRE 16 -1 (-3475 2425)(-3475 2125);
WIRE 16 -1 (-3350 2425)(-3475 2425);
WIRE 16 -1 (-3475 2725)(-3475 2425);
WIRE 16 -1 (-3350 2725)(-3475 2725);
WIRE 16 -1 (-3475 3050)(-3475 2725);
WIRE 16 -1 (-3350 3050)(-3475 3050);
WIRE 16 -1 (-3475 3350)(-3475 3050);
WIRE 16 -1 (-3350 3350)(-3475 3350);
WIRE 16 -1 (-3475 3650)(-3475 3350);
WIRE 16 -1 (-3350 3650)(-3475 3650);
WIRE 16 -1 (-3475 3950)(-3475 3650);
WIRE 16 -1 (-3350 3950)(-3475 3950);
WIRE 16 -1 (-3475 4150)(-3475 3950);
WIRE 16 -1 (450 3475)(650 3475);
WIRE 16 -1 (650 3475)(650 3325);
WIRE 16 -1 (450 3325)(650 3325);
WIRE 16 -1 (650 3325)(650 3175);
WIRE 16 -1 (450 3175)(650 3175);
WIRE 16 -1 (650 3175)(650 3025);
WIRE 16 -1 (450 3025)(650 3025);
WIRE 16 -1 (650 3025)(650 2875);
WIRE 16 -1 (450 2875)(650 2875);
WIRE 16 -1 (650 2875)(650 2725);
WIRE 16 -1 (450 2725)(650 2725);
WIRE 16 -1 (650 2725)(650 2575);
WIRE 16 -1 (450 2575)(650 2575);
WIRE 16 -1 (650 2575)(650 2425);
WIRE 16 -1 (450 2425)(650 2425);
WIRE 16 -1 (650 2425)(650 2275);
WIRE 16 -1 (450 2275)(650 2275);
WIRE 16 -1 (650 2275)(650 2050);
WIRE 16 -1 (-150 3625)(-475 3625);
WIRE 16 -1 (-475 3625)(-475 3475);
WIRE 16 -1 (-150 3475)(-475 3475);
WIRE 16 -1 (-475 3475)(-475 3325);
WIRE 16 -1 (-150 3325)(-475 3325);
WIRE 16 -1 (-475 3325)(-475 3175);
WIRE 16 -1 (-150 3175)(-475 3175);
WIRE 16 -1 (-475 3175)(-475 3025);
WIRE 16 -1 (-150 3025)(-475 3025);
WIRE 16 -1 (-475 3025)(-475 2875);
WIRE 16 -1 (-150 2875)(-475 2875);
WIRE 16 -1 (-475 2875)(-475 2725);
WIRE 16 -1 (-150 2725)(-475 2725);
WIRE 16 -1 (-475 2725)(-475 2575);
WIRE 16 -1 (-150 2575)(-475 2575);
WIRE 16 -1 (-475 2575)(-475 2425);
WIRE 16 -1 (-150 2425)(-475 2425);
WIRE 16 -1 (-475 2425)(-475 2050);
WIRE 16 -1 (3300 1175)(3300 975);
WIRE 16 -1 (3300 975)(2925 975);
WIRE 16 -1 (2925 975)(2925 1200);
WIRE 16 -1 (2925 975)(2400 975);
WIRE 16 -1 (2400 1200)(2400 975);
WIRE 16 -1 (2400 975)(2050 975);
WIRE 16 -1 (2050 975)(2050 1200);
WIRE 16 -1 (1000 975)(2050 975);
WIRE 16 -1 (1000 1200)(1000 975);
WIRE 16 -1 (475 975)(1000 975);
WIRE 16 -1 (475 1200)(475 975);
WIRE 16 -1 (200 975)(475 975);
WIRE 16 -1 (-75 975)(200 975);
WIRE 16 -1 (200 825)(200 975);
WIRE 16 -1 (-75 975)(-525 975);
WIRE 16 -1 (-75 1200)(-75 975);
WIRE 16 -1 (-525 975)(-950 975);
WIRE 16 -1 (-525 975)(-525 1200);
WIRE 16 -1 (-1400 975)(-950 975);
WIRE 16 -1 (-950 1200)(-950 975);
WIRE 16 -1 (-1825 975)(-1400 975);
WIRE 16 -1 (-1400 1200)(-1400 975);
WIRE 16 -1 (-1825 1200)(-1825 975);
WIRE 16 -1 (875 3725)(875 3675);
WIRE 16 -1 (875 3775)(875 3725);
WIRE 16 -1 (875 3725)(450 3725);
WIRE 16 -1 (875 3675)(450 3675);
WIRE 16 -1 (875 3875)(875 3775);
WIRE 16 -1 (875 3775)(450 3775);
WIRE 16 -1 (2400 1400)(2400 1525);
WIRE 16 -1 (2400 1525)(2050 1525);
WIRE 16 -1 (2050 1400)(2050 1525);
WIRE 16 -1 (2050 1525)(2050 1575);
WIRE 16 -1 (1000 1400)(1000 1525);
WIRE 16 -1 (850 1525)(1000 1525);
WIRE 16 -1 (850 1525)(475 1525);
WIRE 16 -1 (850 1525)(850 1575);
WIRE 16 -1 (475 1400)(475 1525);
WIRE 16 -1 (-75 1525)(-75 1400);
WIRE 16 -1 (-75 1525)(-525 1525);
WIRE 16 -1 (-525 1400)(-525 1525);
WIRE 16 -1 (-525 1525)(-950 1525);
WIRE 16 -1 (-950 1400)(-950 1525);
WIRE 16 -1 (-1100 1525)(-950 1525);
WIRE 16 -1 (-1400 1525)(-1100 1525);
WIRE 16 -1 (-1100 1525)(-1100 1575);
WIRE 16 -1 (-1400 1525)(-1825 1525);
WIRE 16 -1 (-1400 1400)(-1400 1525);
WIRE 16 -1 (-1825 1400)(-1825 1525);
WIRE 16 -1 (2925 1400)(2925 1500);
WIRE 16 -1 (3300 1500)(2925 1500);
WIRE 16 -1 (3300 1375)(3300 1500);
WIRE 16 -1 (3300 1600)(3300 1500);
WIRE 16 -1 (1150 4975)(1150 4800);
WIRE 16 -1 (1150 4975)(425 4975);
WIRE 16 -1 (1150 4700)(1150 4800);
WIRE 16 -1 (-3625 4800)(1150 4800);
WIRE 16 -1 (-3625 4975)(-3625 4800);
WIRE 16 -1 (-3625 4700)(-3625 4800);
WIRE 16 -1 (1150 4600)(1150 4700);
WIRE 16 -1 (-3625 4700)(1150 4700);
WIRE 16 -1 (425 4975)(425 4500);
WIRE 16 -1 (425 4975)(-225 4975);
WIRE 16 -1 (-225 4975)(-225 4500);
WIRE 16 -1 (-225 4975)(-925 4975);
WIRE 16 -1 (1150 4500)(425 4500);
WIRE 16 -1 (425 4500)(-225 4500);
WIRE 16 -1 (-3625 4700)(-3625 4600);
WIRE 16 -1 (1150 4600)(1150 4500);
WIRE 16 -1 (-3625 4600)(1150 4600);
WIRE 16 -1 (-3625 4975)(-3325 4975);
WIRE 16 -1 (-3325 4975)(-2475 4975);
WIRE 16 -1 (-3325 4975)(-3325 4500);
WIRE 16 -1 (-3625 4600)(-3625 4500);
WIRE 16 -1 (-225 4500)(-925 4500);
WIRE 16 -1 (-925 4975)(-925 4500);
WIRE 16 -1 (-925 4975)(-1600 4975);
WIRE 16 -1 (-1600 4975)(-2475 4975);
WIRE 16 -1 (-1600 4975)(-1600 4500);
WIRE 16 -1 (-925 4500)(-1600 4500);
WIRE 16 -1 (-3625 4500)(-3325 4500);
WIRE 16 -1 (-3325 4500)(-2475 4500);
WIRE 16 -1 (-2475 4975)(-2475 4500);
WIRE 16 -1 (-1600 4500)(-2475 4500);
WIRE 16 -1 (-3150 1825)(-2500 1825);
FORCEPROP 2 LAST SIG_NAME SMB_PCH_MEZZ_LOM3_SDA
J 0
(-3050 1835);
DISPLAY 0.617021 (-3050 1835);
PAINT ORANGE (-3050 1835);
WIRE 16 -1 (-3150 2425)(-2500 2425);
FORCEPROP 2 LAST SIG_NAME SMB_PCH_MEZZ_LOM2_SDA
J 0
(-3050 2435);
DISPLAY 0.617021 (-3050 2435);
PAINT ORANGE (-3050 2435);
WIRE 16 -1 (-3150 3050)(-2500 3050);
FORCEPROP 2 LAST SIG_NAME SMB_PCH_MEZZ_LOM1_SDA
J 0
(-3050 3060);
DISPLAY 0.617021 (-3050 3060);
PAINT ORANGE (-3050 3060);
WIRE 16 -1 (-3150 3650)(-2500 3650);
FORCEPROP 2 LAST SIG_NAME SMB_PCH_MEZZ_LOM0_SDA
J 0
(-3050 3660);
DISPLAY 0.617021 (-3050 3660);
PAINT ORANGE (-3050 3660);
WIRE 16 -1 (-3150 3950)(-2500 3950);
FORCEPROP 2 LAST SIG_NAME SMB_PCH_MEZZ_LOM0_SCL
J 0
(-3050 3960);
DISPLAY 0.617021 (-3050 3960);
PAINT ORANGE (-3050 3960);
WIRE 16 -1 (-3150 3350)(-2500 3350);
FORCEPROP 2 LAST SIG_NAME SMB_PCH_MEZZ_LOM1_SCL
J 0
(-3050 3360);
DISPLAY 0.617021 (-3050 3360);
PAINT ORANGE (-3050 3360);
WIRE 16 -1 (-3150 2725)(-2500 2725);
FORCEPROP 2 LAST SIG_NAME SMB_PCH_MEZZ_LOM2_SCL
J 0
(-3050 2735);
DISPLAY 0.617021 (-3050 2735);
PAINT ORANGE (-3050 2735);
WIRE 16 -1 (-3150 2125)(-2500 2125);
FORCEPROP 2 LAST SIG_NAME SMB_PCH_MEZZ_LOM3_SCL
J 0
(-3050 2135);
DISPLAY 0.617021 (-3050 2135);
PAINT ORANGE (-3050 2135);
WIRE 16 -1 (-150 3675)(-1325 3675);
FORCEPROP 0 LAST SIG_NAME TP_EXT_MDIO_I2C_SEL
J 0
(-1300 3685);
DISPLAY 0.617021 (-1300 3685);
PAINT ORANGE (-1300 3685);
FORCEPROP 2 LASTPROP $XRERR UNIQUE?
J 0
(-1565 3675);
DISPLAY 0.638298 (-1565 3675);
PAINT MONO (-1565 3675);
DISPLAY INVISIBLE (-1565 3675);
WIRE 16 -1 (-150 2475)(-1350 2475);
FORCEPROP 0 LAST SIG_NAME SMB_PCH_MEZZ_LOM1_SDA
J 0
(-1300 2485);
DISPLAY 0.617021 (-1300 2485);
PAINT ORANGE (-1300 2485);
WIRE 16 -1 (-150 2525)(-1350 2525);
FORCEPROP 0 LAST SIG_NAME SMB_PCH_MEZZ_LOM1_SCL
J 0
(-1300 2535);
DISPLAY 0.617021 (-1300 2535);
PAINT ORANGE (-1300 2535);
WIRE 16 -1 (-150 2325)(-1350 2325);
FORCEPROP 0 LAST SIG_NAME SMB_PCH_MEZZ_LOM3_SDA
J 0
(-1300 2335);
DISPLAY 0.617021 (-1300 2335);
PAINT ORANGE (-1300 2335);
WIRE 16 -1 (-150 2375)(-1350 2375);
FORCEPROP 0 LAST SIG_NAME SMB_PCH_MEZZ_LOM3_SCL
J 0
(-1300 2385);
DISPLAY 0.617021 (-1300 2385);
PAINT ORANGE (-1300 2385);
WIRE 16 -1 (-150 2825)(-1350 2825);
FORCEPROP 0 LAST SIG_NAME SMB_PCH_MEZZ_LOM0_SCL
J 0
(-1300 2835);
DISPLAY 0.617021 (-1300 2835);
PAINT ORANGE (-1300 2835);
WIRE 16 -1 (-150 2775)(-1350 2775);
FORCEPROP 0 LAST SIG_NAME SMB_PCH_MEZZ_LOM0_SDA
J 0
(-1300 2785);
DISPLAY 0.617021 (-1300 2785);
PAINT ORANGE (-1300 2785);
WIRE 16 -1 (-150 2275)(-1350 2275);
FORCEPROP 0 LAST SIG_NAME FM_GBE2_LVC3_MOD_ABS
J 0
(-1300 2285);
DISPLAY 0.617021 (-1300 2285);
PAINT ORANGE (-1300 2285);
WIRE 16 -1 (-150 2225)(-1350 2225);
FORCEPROP 0 LAST SIG_NAME FM_GBE3_LVC3_MOD_ABS
J 0
(-1300 2235);
DISPLAY 0.617021 (-1300 2235);
PAINT ORANGE (-1300 2235);
WIRE 16 -1 (-150 3775)(-1350 3775);
FORCEPROP 0 LAST SIG_NAME SMB_OCP_FRU_STBY_LVC3_SCL
J 0
(-1300 3785);
DISPLAY 0.617021 (-1300 3785);
PAINT ORANGE (-1300 3785);
WIRE 16 -1 (-150 3725)(-1350 3725);
FORCEPROP 0 LAST SIG_NAME SMB_OCP_FRU_STBY_LVC3_SDA
J 0
(-1300 3735);
DISPLAY 0.617021 (-1300 3735);
PAINT ORANGE (-1300 3735);
WIRE 16 -1 (-150 3575)(-1350 3575);
FORCEPROP 2 LAST SIG_NAME KR_P2_OCP_TX_DP
J 0
(-1300 3585);
DISPLAY 0.617021 (-1300 3585);
PAINT ORANGE (-1300 3585);
WIRE 16 -1 (-150 3525)(-1350 3525);
FORCEPROP 2 LAST SIG_NAME KR_P2_OCP_TX_DN
J 0
(-1300 3535);
DISPLAY 0.617021 (-1300 3535);
PAINT ORANGE (-1300 3535);
WIRE 16 -1 (-150 3425)(-1350 3425);
FORCEPROP 0 LAST SIG_NAME LED_GBE_P1_0
J 0
(-1300 3435);
DISPLAY 0.617021 (-1300 3435);
PAINT ORANGE (-1300 3435);
WIRE 16 -1 (-150 3375)(-1350 3375);
FORCEPROP 0 LAST SIG_NAME LED_GBE_P1_1
J 0
(-1300 3385);
DISPLAY 0.617021 (-1300 3385);
PAINT ORANGE (-1300 3385);
WIRE 16 -1 (-150 3275)(-1350 3275);
FORCEPROP 2 LAST SIG_NAME KR_P3_OCP_TX_DP
J 0
(-1300 3285);
DISPLAY 0.617021 (-1300 3285);
PAINT ORANGE (-1300 3285);
WIRE 16 -1 (-150 3225)(-1350 3225);
FORCEPROP 2 LAST SIG_NAME KR_P3_OCP_TX_DN
J 0
(-1300 3235);
DISPLAY 0.617021 (-1300 3235);
PAINT ORANGE (-1300 3235);
WIRE 16 -1 (-150 3075)(-1350 3075);
FORCEPROP 0 LAST SIG_NAME LED_GBE_P2_1
J 0
(-1300 3085);
DISPLAY 0.617021 (-1300 3085);
PAINT ORANGE (-1300 3085);
WIRE 16 -1 (-150 3125)(-1350 3125);
FORCEPROP 0 LAST SIG_NAME LED_GBE_P2_0
J 0
(-1300 3135);
DISPLAY 0.617021 (-1300 3135);
PAINT ORANGE (-1300 3135);
WIRE 16 -1 (-150 2975)(-1350 2975);
FORCEPROP 2 LAST SIG_NAME KR_P2_OCP_RX_DP
J 0
(-1300 2985);
DISPLAY 0.617021 (-1300 2985);
PAINT ORANGE (-1300 2985);
WIRE 16 -1 (-150 2925)(-1350 2925);
FORCEPROP 2 LAST SIG_NAME KR_P2_OCP_RX_DN
J 0
(-1300 2935);
DISPLAY 0.617021 (-1300 2935);
PAINT ORANGE (-1300 2935);
WIRE 16 -1 (-150 2675)(-1350 2675);
FORCEPROP 2 LAST SIG_NAME KR_P3_OCP_RX_DP
J 0
(-1300 2685);
DISPLAY 0.617021 (-1300 2685);
PAINT ORANGE (-1300 2685);
WIRE 16 -1 (-150 2625)(-1350 2625);
FORCEPROP 2 LAST SIG_NAME KR_P3_OCP_RX_DN
J 0
(-1300 2635);
DISPLAY 0.617021 (-1300 2635);
PAINT ORANGE (-1300 2635);
WIRE 16 -1 (1375 3625)(450 3625);
FORCEPROP 0 LAST SIG_NAME TP_RSVD<0>
J 0
(775 3635);
DISPLAY 0.617021 (775 3635);
PAINT ORANGE (775 3635);
FORCEPROP 2 LASTPROP $XRERR UNIQUE?
J 0
(1405 3625);
DISPLAY 0.638298 (1405 3625);
PAINT MONO (1405 3625);
DISPLAY INVISIBLE (1405 3625);
WIRE 16 -1 (1375 2975)(450 2975);
FORCEPROP 0 LAST SIG_NAME TP_SHARED_KR_MDC_0
J 0
(775 2985);
DISPLAY 0.617021 (775 2985);
PAINT ORANGE (775 2985);
FORCEPROP 2 LASTPROP $XRERR UNIQUE?
J 0
(1405 2975);
DISPLAY 0.638298 (1405 2975);
PAINT MONO (1405 2975);
DISPLAY INVISIBLE (1405 2975);
WIRE 16 -1 (1375 2925)(450 2925);
FORCEPROP 0 LAST SIG_NAME TP_SHARED_KR_MDIO_0
J 0
(775 2935);
DISPLAY 0.617021 (775 2935);
PAINT ORANGE (775 2935);
FORCEPROP 2 LASTPROP $XRERR UNIQUE?
J 0
(1405 2925);
DISPLAY 0.638298 (1405 2925);
PAINT MONO (1405 2925);
DISPLAY INVISIBLE (1405 2925);
WIRE 16 -1 (1350 3075)(450 3075);
FORCEPROP 2 LAST SIG_NAME KR_P1_OCP_TX_DN
J 0
(775 3085);
DISPLAY 0.617021 (775 3085);
PAINT ORANGE (775 3085);
WIRE 16 -1 (1350 3125)(450 3125);
FORCEPROP 2 LAST SIG_NAME KR_P1_OCP_TX_DP
J 0
(775 3135);
DISPLAY 0.617021 (775 3135);
PAINT ORANGE (775 3135);
WIRE 16 -1 (1350 2325)(450 2325);
FORCEPROP 0 LAST SIG_NAME SMB_PCH_MEZZ_LOM2_SDA
J 0
(775 2335);
DISPLAY 0.617021 (775 2335);
PAINT ORANGE (775 2335);
WIRE 16 -1 (1350 2375)(450 2375);
FORCEPROP 0 LAST SIG_NAME SMB_PCH_MEZZ_LOM2_SCL
J 0
(775 2385);
DISPLAY 0.617021 (775 2385);
PAINT ORANGE (775 2385);
WIRE 16 -1 (1350 3525)(450 3525);
FORCEPROP 0 LAST SIG_NAME FM_GBE1_LVC3_MOD_ABS
J 0
(775 3535);
DISPLAY 0.617021 (775 3535);
PAINT ORANGE (775 3535);
WIRE 16 -1 (1350 3575)(450 3575);
FORCEPROP 0 LAST SIG_NAME FM_GBE0_LVC3_MOD_ABS
J 0
(775 3585);
DISPLAY 0.617021 (775 3585);
PAINT ORANGE (775 3585);
WIRE 16 -1 (1375 2225)(450 2225);
FORCEPROP 0 LAST SIG_NAME FM_OCP_MEZZC_PRES_N
J 0
(775 2235);
DISPLAY 0.617021 (775 2235);
PAINT ORANGE (775 2235);
WIRE 16 -1 (1350 2825)(450 2825);
FORCEPROP 2 LAST SIG_NAME KR_P0_OCP_RX_DP
J 0
(775 2835);
DISPLAY 0.617021 (775 2835);
PAINT ORANGE (775 2835);
WIRE 16 -1 (1350 2775)(450 2775);
FORCEPROP 2 LAST SIG_NAME KR_P0_OCP_RX_DN
J 0
(775 2785);
DISPLAY 0.617021 (775 2785);
PAINT ORANGE (775 2785);
WIRE 16 -1 (1350 2675)(450 2675);
FORCEPROP 0 LAST SIG_NAME LED_GBE_P3_0
J 0
(775 2685);
DISPLAY 0.617021 (775 2685);
PAINT ORANGE (775 2685);
WIRE 16 -1 (1350 2625)(450 2625);
FORCEPROP 0 LAST SIG_NAME LED_GBE_P3_1
J 0
(775 2635);
DISPLAY 0.617021 (775 2635);
PAINT ORANGE (775 2635);
WIRE 16 -1 (1350 2525)(450 2525);
FORCEPROP 2 LAST SIG_NAME KR_P1_OCP_RX_DP
J 0
(775 2535);
DISPLAY 0.617021 (775 2535);
PAINT ORANGE (775 2535);
WIRE 16 -1 (1350 2475)(450 2475);
FORCEPROP 2 LAST SIG_NAME KR_P1_OCP_RX_DN
J 0
(775 2485);
DISPLAY 0.617021 (775 2485);
PAINT ORANGE (775 2485);
WIRE 16 -1 (1350 3425)(450 3425);
FORCEPROP 2 LAST SIG_NAME KR_P0_OCP_TX_DP
J 0
(775 3435);
DISPLAY 0.617021 (775 3435);
PAINT ORANGE (775 3435);
WIRE 16 -1 (1350 3375)(450 3375);
FORCEPROP 2 LAST SIG_NAME KR_P0_OCP_TX_DN
J 0
(775 3385);
DISPLAY 0.617021 (775 3385);
PAINT ORANGE (775 3385);
WIRE 16 -1 (1350 3275)(450 3275);
FORCEPROP 0 LAST SIG_NAME LED_GBE_P0_0
J 0
(775 3285);
DISPLAY 0.617021 (775 3285);
PAINT ORANGE (775 3285);
WIRE 16 -1 (1350 3225)(450 3225);
FORCEPROP 0 LAST SIG_NAME LED_GBE_P0_1
J 0
(775 3235);
DISPLAY 0.617021 (775 3235);
PAINT ORANGE (775 3235);
WIRE 16 -1 (2975 2925)(2425 2925);
FORCEPROP 2 LAST SIG_NAME KR_P0_OCP_RX_DP
J 0
(2490 2935);
DISPLAY 0.617021 (2490 2935);
PAINT ORANGE (2490 2935);
WIRE 16 -1 (2975 2600)(2425 2600);
FORCEPROP 2 LAST SIG_NAME KR_P0_OCP_RX_DN
J 0
(2490 2610);
DISPLAY 0.617021 (2490 2610);
PAINT ORANGE (2490 2610);
WIRE 16 -1 (2975 3925)(2425 3925);
FORCEPROP 2 LAST SIG_NAME KR_P2_OCP_RX_DN
J 0
(2490 3935);
DISPLAY 0.617021 (2490 3935);
PAINT ORANGE (2490 3935);
WIRE 16 -1 (2975 3600)(2425 3600);
FORCEPROP 2 LAST SIG_NAME KR_P1_OCP_RX_DP
J 0
(2490 3610);
DISPLAY 0.617021 (2490 3610);
PAINT ORANGE (2490 3610);
WIRE 16 -1 (2975 3275)(2425 3275);
FORCEPROP 2 LAST SIG_NAME KR_P1_OCP_RX_DN
J 0
(2490 3285);
DISPLAY 0.617021 (2490 3285);
PAINT ORANGE (2490 3285);
WIRE 16 -1 (3175 2600)(3725 2600);
FORCEPROP 2 LAST SIG_NAME KR_P0_OCP_RX_C_DN
J 0
(3290 2610);
DISPLAY 0.617021 (3290 2610);
PAINT ORANGE (3290 2610);
WIRE 16 -1 (3175 2925)(3725 2925);
FORCEPROP 2 LAST SIG_NAME KR_P0_OCP_RX_C_DP
J 0
(3290 2935);
DISPLAY 0.617021 (3290 2935);
PAINT ORANGE (3290 2935);
WIRE 16 -1 (3175 3925)(3725 3925);
FORCEPROP 2 LAST SIG_NAME KR_P2_OCP_RX_C_DN
J 0
(3290 3935);
DISPLAY 0.617021 (3290 3935);
PAINT ORANGE (3290 3935);
WIRE 16 -1 (3175 3600)(3725 3600);
FORCEPROP 2 LAST SIG_NAME KR_P1_OCP_RX_C_DP
J 0
(3290 3610);
DISPLAY 0.617021 (3290 3610);
PAINT ORANGE (3290 3610);
WIRE 16 -1 (3175 3275)(3725 3275);
FORCEPROP 2 LAST SIG_NAME KR_P1_OCP_RX_C_DN
J 0
(3265 3285);
DISPLAY 0.617021 (3265 3285);
PAINT ORANGE (3265 3285);
WIRE 16 -1 (2975 4925)(2425 4925);
FORCEPROP 2 LAST SIG_NAME KR_P3_OCP_RX_DP
J 0
(2465 4935);
DISPLAY 0.617021 (2465 4935);
PAINT ORANGE (2465 4935);
WIRE 16 -1 (2975 4600)(2425 4600);
FORCEPROP 2 LAST SIG_NAME KR_P3_OCP_RX_DN
J 0
(2490 4610);
DISPLAY 0.617021 (2490 4610);
PAINT ORANGE (2490 4610);
WIRE 16 -1 (2975 4250)(2425 4250);
FORCEPROP 2 LAST SIG_NAME KR_P2_OCP_RX_DP
J 0
(2490 4260);
DISPLAY 0.617021 (2490 4260);
PAINT ORANGE (2490 4260);
WIRE 16 -1 (3175 4925)(3725 4925);
FORCEPROP 2 LAST SIG_NAME KR_P3_OCP_RX_C_DP
J 0
(3265 4935);
DISPLAY 0.617021 (3265 4935);
PAINT ORANGE (3265 4935);
WIRE 16 -1 (3175 4600)(3725 4600);
FORCEPROP 2 LAST SIG_NAME KR_P3_OCP_RX_C_DN
J 0
(3265 4610);
DISPLAY 0.617021 (3265 4610);
PAINT ORANGE (3265 4610);
WIRE 16 -1 (3175 4250)(3725 4250);
FORCEPROP 2 LAST SIG_NAME KR_P2_OCP_RX_C_DP
J 0
(3290 4260);
DISPLAY 0.617021 (3290 4260);
PAINT ORANGE (3290 4260);
DOT 1 (875 3775);
DOT 1 (875 3725);
DOT 1 (-3625 4600);
DOT 1 (-3625 4700);
DOT 1 (-3625 4800);
DOT 1 (-3325 4975);
DOT 1 (-3325 4500);
DOT 1 (-2475 4975);
DOT 1 (-2475 4500);
DOT 1 (-1600 4975);
DOT 1 (-925 4975);
DOT 1 (-925 4500);
DOT 1 (-225 4975);
DOT 1 (-225 4500);
DOT 1 (425 4975);
DOT 1 (1150 4800);
DOT 1 (1150 4700);
DOT 1 (-475 3025);
DOT 1 (650 2575);
DOT 1 (-475 2425);
DOT 1 (650 3325);
DOT 1 (650 3175);
DOT 1 (650 3025);
DOT 1 (650 2875);
DOT 1 (650 2725);
DOT 1 (650 2275);
DOT 1 (-475 3475);
DOT 1 (-475 3325);
DOT 1 (-475 2725);
DOT 1 (-475 2575);
DOT 1 (-3475 3950);
DOT 1 (-3475 3650);
DOT 1 (-3475 3350);
DOT 1 (-3475 3050);
DOT 1 (-3475 2725);
DOT 1 (-3475 2425);
DOT 1 (-3475 2125);
DOT 1 (3300 1500);
DOT 1 (2925 975);
DOT 1 (2050 1525);
DOT 1 (2400 975);
DOT 1 (2050 975);
DOT 1 (850 1525);
DOT 1 (1000 975);
DOT 1 (475 975);
DOT 1 (200 975);
DOT 1 (-75 975);
DOT 1 (-525 1525);
DOT 1 (-950 1525);
DOT 1 (-1100 1525);
DOT 1 (-1400 1525);
DOT 1 (-950 975);
DOT 1 (-525 975);
DOT 1 (-1400 975);
DOT 1 (-475 2875);
DOT 1 (1150 4600);
DOT 1 (-1600 4500);
DOT 1 (425 4500);
DOT 1 (-475 3175);
DOT 1 (650 2425);
FORCENOTE
61083-121402LF
(-3275 4725) 0;
DISPLAY LEFT (-3275 4725);
DISPLAY 1.021277 (-3275 4725);
PAINT PURPLE (-3275 4725);
FORCENOTE
ROOM = IO_MODULE
(-3600 400) 0;
DISPLAY LEFT (-3600 400);
DISPLAY 0.808511 (-3600 400);
PAINT PURPLE (-3600 400);
FORCENOTE
B (80P)
(-3600 4625) 0;
DISPLAY LEFT (-3600 4625);
DISPLAY 1.021277 (-3600 4625);
PAINT PURPLE (-3600 4625);
FORCENOTE
A (120P)
(-3600 4725) 0;
DISPLAY LEFT (-3600 4725);
DISPLAY 1.021277 (-3600 4725);
PAINT PURPLE (-3600 4725);
FORCENOTE
CONN
(-3600 4900) 0;
DISPLAY LEFT (-3600 4900);
DISPLAY 1.021277 (-3600 4900);
PAINT PURPLE (-3600 4900);
FORCENOTE
10135584-641402LF
(-3275 4525) 0;
DISPLAY LEFT (-3275 4525);
DISPLAY 1.021277 (-3275 4525);
PAINT PURPLE (-3275 4525);
FORCENOTE
61083-124402LF
(-2425 4725) 0;
DISPLAY LEFT (-2425 4725);
DISPLAY 1.021277 (-2425 4725);
PAINT PURPLE (-2425 4725);
FORCENOTE
61083-084402LF
(-2425 4625) 0;
DISPLAY LEFT (-2425 4625);
DISPLAY 1.021277 (-2425 4625);
PAINT PURPLE (-2425 4625);
FORCENOTE
(8/12 MM STACK)
(-2425 4825) 0;
DISPLAY LEFT (-2425 4825);
DISPLAY 1.021277 (-2425 4825);
PAINT PURPLE (-2425 4825);
FORCENOTE
10135584-644402LF
(-2425 4525) 0;
DISPLAY LEFT (-2425 4525);
DISPLAY 1.021277 (-2425 4525);
PAINT PURPLE (-2425 4525);
FORCENOTE
FCI RECPT # ON CC
(-1550 4900) 0;
DISPLAY LEFT (-1550 4900);
DISPLAY 1.021277 (-1550 4900);
PAINT PURPLE (-1550 4900);
FORCENOTE
10135583-641402LF
(-1550 4525) 0;
DISPLAY LEFT (-1550 4525);
DISPLAY 1.021277 (-1550 4525);
PAINT PURPLE (-1550 4525);
FORCENOTE
61082-081402LF
(-1550 4625) 0;
DISPLAY LEFT (-1550 4625);
DISPLAY 1.021277 (-1550 4625);
PAINT PURPLE (-1550 4625);
FORCENOTE
61082-121402LF
(-1550 4725) 0;
DISPLAY LEFT (-1550 4725);
DISPLAY 1.021277 (-1550 4725);
PAINT PURPLE (-1550 4725);
FORCENOTE
(5/8MM STACK)
(-1550 4825) 0;
DISPLAY LEFT (-1550 4825);
DISPLAY 1.021277 (-1550 4825);
PAINT PURPLE (-1550 4825);
FORCENOTE
H87568-001
(-875 4525) 0;
DISPLAY LEFT (-875 4525);
DISPLAY 1.021277 (-875 4525);
PAINT PURPLE (-875 4525);
FORCENOTE
E67482-006
(-875 4625) 0;
DISPLAY LEFT (-875 4625);
DISPLAY 1.021277 (-875 4625);
PAINT PURPLE (-875 4625);
FORCENOTE
A28699-010
(-875 4725) 0;
DISPLAY LEFT (-875 4725);
DISPLAY 1.021277 (-875 4725);
PAINT PURPLE (-875 4725);
FORCENOTE
(5/8MM STACK)
(-900 4825) 0;
DISPLAY LEFT (-900 4825);
DISPLAY 1.021277 (-900 4825);
PAINT PURPLE (-900 4825);
FORCENOTE
FCI RECPT # ON CC
(-200 4900) 0;
DISPLAY LEFT (-200 4900);
DISPLAY 1.021277 (-200 4900);
PAINT PURPLE (-200 4900);
FORCENOTE
61082-082402LF
(-200 4625) 0;
DISPLAY LEFT (-200 4625);
DISPLAY 1.021277 (-200 4625);
PAINT PURPLE (-200 4625);
FORCENOTE
FCI RECPT IPN ON CC
(-900 4900) 0;
DISPLAY LEFT (-900 4900);
DISPLAY 1.021277 (-900 4900);
PAINT PURPLE (-900 4900);
FORCENOTE
(12MM STACK)
(-200 4825) 0;
DISPLAY LEFT (-200 4825);
DISPLAY 1.021277 (-200 4825);
PAINT PURPLE (-200 4825);
FORCENOTE
61082-122402LF
(-200 4725) 0;
DISPLAY LEFT (-200 4725);
DISPLAY 1.021277 (-200 4725);
PAINT PURPLE (-200 4725);
FORCENOTE
10135583-642402LF
(-200 4525) 0;
DISPLAY LEFT (-200 4525);
DISPLAY 1.021277 (-200 4525);
PAINT PURPLE (-200 4525);
FORCENOTE
H87568-002
(450 4525) 0;
DISPLAY LEFT (450 4525);
DISPLAY 1.021277 (450 4525);
PAINT PURPLE (450 4525);
FORCENOTE
A28699-020
(450 4725) 0;
DISPLAY LEFT (450 4725);
DISPLAY 1.021277 (450 4725);
PAINT PURPLE (450 4725);
FORCENOTE
E67482-008
(450 4625) 0;
DISPLAY LEFT (450 4625);
DISPLAY 1.021277 (450 4625);
PAINT PURPLE (450 4625);
FORCENOTE
(12 MM STACK)
(450 4825) 0;
DISPLAY LEFT (450 4825);
DISPLAY 1.021277 (450 4825);
PAINT PURPLE (450 4825);
FORCENOTE
FCI RECPT IPN ON CC
(450 4900) 0;
DISPLAY LEFT (450 4900);
DISPLAY 1.021277 (450 4900);
PAINT PURPLE (450 4900);
FORCENOTE
61082-081402LF
(-3275 4625) 0;
DISPLAY LEFT (-3275 4625);
DISPLAY 1.021277 (-3275 4625);
PAINT PURPLE (-3275 4625);
FORCENOTE
FCI PLUG # ON OCP MEZZ
(-2425 4900) 0;
DISPLAY LEFT (-2425 4900);
DISPLAY 1.021277 (-2425 4900);
PAINT PURPLE (-2425 4900);
FORCENOTE
C (64P)
(-3600 4525) 0;
DISPLAY LEFT (-3600 4525);
DISPLAY 1.021277 (-3600 4525);
PAINT PURPLE (-3600 4525);
FORCENOTE
(5MM STACK)
(-3275 4825) 0;
DISPLAY LEFT (-3275 4825);
DISPLAY 1.021277 (-3275 4825);
PAINT PURPLE (-3275 4825);
FORCENOTE
FCI PLUG # ON OCP MEZZ
(-3275 4900) 0;
DISPLAY LEFT (-3275 4900);
DISPLAY 1.021277 (-3275 4900);
PAINT PURPLE (-3275 4900);
FORCENOTE
MATED HT CONNECTOR P/NS
(-3600 5000) 0;
DISPLAY LEFT (-3600 5000);
DISPLAY 1.021277 (-3600 5000);
PAINT PURPLE (-3600 5000);
QUIT
